FILE_TYPE = MACRO_DRAWING;
SET COLOR_WIRE YELLOW;
SET COLOR_PROP ORANGE;
SET COLOR_DOT WHITE;
SET COLOR_ARC YELLOW;
SET COLOR_BODY GREEN;
SET COLOR_NOTE PURPLE;
SET PROP_DISPLAY VALUE;
SET PAGE_NUMBER P326;
FORCEADD OFFPAGE..1
(-1125 200);
FORCEPROP 2 LAST $XR0 309 
J 0
(-1377 200);
DISPLAY 0.638298 (-1377 200);
PAINT MONO (-1377 200);
FORCEPROP 2 LAST CDS_LIB standard
J 0
(-1125 200);
DISPLAY INVISIBLE (-1125 200);
FORCEPROP 1 LAST OFFPAGE TRUE
J 0
(-800 75);
DISPLAY 0.872340 (-800 75);
PAINT AQUA (-800 75);
DISPLAY INVISIBLE (-800 75);
FORCEPROP 1 LAST COMMENT_BODY TRUE
J 0
(-1000 100);
DISPLAY 0.872340 (-1000 100);
PAINT GREEN (-1000 100);
DISPLAY INVISIBLE (-1000 100);
FORCEPROP 2 LAST PATH I1
J 0
(-1375 250);
DISPLAY 0.680851 (-1375 250);
DISPLAY INVISIBLE (-1375 250);
FORCEADD OFFPAGE..4
R 2
(-1125 900);
FORCEPROP 2 LAST $XR0 130 
J 0
(-1377 900);
DISPLAY 0.638298 (-1377 900);
PAINT MONO (-1377 900);
FORCEPROP 2 LAST CDS_LIB standard
J 0
(-1125 900);
DISPLAY INVISIBLE (-1125 900);
FORCEPROP 1 LAST OFFPAGE TRUE
J 2
(-1450 775);
DISPLAY 0.872340 (-1450 775);
PAINT GREEN (-1450 775);
DISPLAY INVISIBLE (-1450 775);
FORCEPROP 1 LAST COMMENT_BODY TRUE
J 2
(-1100 800);
DISPLAY 0.872340 (-1100 800);
PAINT GREEN (-1100 800);
DISPLAY INVISIBLE (-1100 800);
FORCEPROP 2 LAST PATH I10
J 0
(-1375 950);
DISPLAY 0.680851 (-1375 950);
DISPLAY INVISIBLE (-1375 950);
FORCEADD OFFPAGE..1
(-1125 1000);
FORCEPROP 2 LAST $XR0 309 
J 0
(-1377 1000);
DISPLAY 0.638298 (-1377 1000);
PAINT MONO (-1377 1000);
FORCEPROP 2 LAST CDS_LIB standard
J 0
(-1125 1000);
DISPLAY INVISIBLE (-1125 1000);
FORCEPROP 1 LAST OFFPAGE TRUE
J 0
(-800 875);
DISPLAY 0.872340 (-800 875);
PAINT AQUA (-800 875);
DISPLAY INVISIBLE (-800 875);
FORCEPROP 1 LAST COMMENT_BODY TRUE
J 0
(-1000 900);
DISPLAY 0.872340 (-1000 900);
PAINT GREEN (-1000 900);
DISPLAY INVISIBLE (-1000 900);
FORCEPROP 2 LAST PATH I11
J 0
(-1375 1050);
DISPLAY 0.680851 (-1375 1050);
DISPLAY INVISIBLE (-1375 1050);
FORCEADD OFFPAGE..1
(-1125 1050);
FORCEPROP 2 LAST $XR0 309 
J 0
(-1377 1050);
DISPLAY 0.638298 (-1377 1050);
PAINT MONO (-1377 1050);
FORCEPROP 2 LAST CDS_LIB standard
J 0
(-1125 1050);
DISPLAY INVISIBLE (-1125 1050);
FORCEPROP 1 LAST OFFPAGE TRUE
J 0
(-800 925);
DISPLAY 0.872340 (-800 925);
PAINT AQUA (-800 925);
DISPLAY INVISIBLE (-800 925);
FORCEPROP 1 LAST COMMENT_BODY TRUE
J 0
(-1000 950);
DISPLAY 0.872340 (-1000 950);
PAINT GREEN (-1000 950);
DISPLAY INVISIBLE (-1000 950);
FORCEPROP 2 LAST PATH I12
J 0
(-1375 1100);
DISPLAY 0.680851 (-1375 1100);
DISPLAY INVISIBLE (-1375 1100);
FORCEADD OFFPAGE..1
(-1125 1200);
FORCEPROP 2 LAST $XR0 298 
J 0
(-1377 1200);
DISPLAY 0.638298 (-1377 1200);
PAINT MONO (-1377 1200);
FORCEPROP 2 LAST CDS_LIB standard
J 0
(-1125 1200);
DISPLAY INVISIBLE (-1125 1200);
FORCEPROP 1 LAST OFFPAGE TRUE
J 0
(-800 1075);
DISPLAY 0.872340 (-800 1075);
PAINT AQUA (-800 1075);
DISPLAY INVISIBLE (-800 1075);
FORCEPROP 1 LAST COMMENT_BODY TRUE
J 0
(-1000 1100);
DISPLAY 0.872340 (-1000 1100);
PAINT GREEN (-1000 1100);
DISPLAY INVISIBLE (-1000 1100);
FORCEPROP 2 LAST PATH I13
J 0
(-1375 1250);
DISPLAY 0.680851 (-1375 1250);
DISPLAY INVISIBLE (-1375 1250);
FORCEADD OFFPAGE..1
(-1125 1150);
FORCEPROP 2 LAST $XR0 298 
J 0
(-1377 1150);
DISPLAY 0.638298 (-1377 1150);
PAINT MONO (-1377 1150);
FORCEPROP 2 LAST CDS_LIB standard
J 0
(-1125 1150);
DISPLAY INVISIBLE (-1125 1150);
FORCEPROP 1 LAST OFFPAGE TRUE
J 0
(-800 1025);
DISPLAY 0.872340 (-800 1025);
PAINT AQUA (-800 1025);
DISPLAY INVISIBLE (-800 1025);
FORCEPROP 1 LAST COMMENT_BODY TRUE
J 0
(-1000 1050);
DISPLAY 0.872340 (-1000 1050);
PAINT GREEN (-1000 1050);
DISPLAY INVISIBLE (-1000 1050);
FORCEPROP 2 LAST PATH I14
J 0
(-1375 1200);
DISPLAY 0.680851 (-1375 1200);
DISPLAY INVISIBLE (-1375 1200);
FORCEADD OFFPAGE..5
(-1125 1300);
FORCEPROP 2 LAST $XR0 308 
J 0
(-1410 1300);
DISPLAY 0.638298 (-1410 1300);
PAINT MONO (-1410 1300);
FORCEPROP 2 LAST CDS_LIB standard
J 0
(-1125 1300);
DISPLAY INVISIBLE (-1125 1300);
FORCEPROP 1 LAST OFFPAGE TRUE
J 0
(-800 1175);
DISPLAY 0.872340 (-800 1175);
PAINT AQUA (-800 1175);
DISPLAY INVISIBLE (-800 1175);
FORCEPROP 1 LAST COMMENT_BODY TRUE
J 0
(-1025 1225);
DISPLAY 1.170213 (-1025 1225);
PAINT GREEN (-1025 1225);
DISPLAY INVISIBLE (-1025 1225);
FORCEPROP 2 LAST PATH I15
J 0
(-1400 1350);
DISPLAY 0.680851 (-1400 1350);
DISPLAY INVISIBLE (-1400 1350);
FORCEADD OFFPAGE..2
R 2
(-1125 1500);
FORCEPROP 2 LAST $XR0 297 
J 0
(-1410 1500);
DISPLAY 0.638298 (-1410 1500);
PAINT MONO (-1410 1500);
FORCEPROP 2 LAST CDS_LIB standard
J 0
(-1125 1500);
DISPLAY INVISIBLE (-1125 1500);
FORCEPROP 1 LAST OFFPAGE TRUE
J 2
(-1450 1375);
DISPLAY 0.872340 (-1450 1375);
PAINT AQUA (-1450 1375);
DISPLAY INVISIBLE (-1450 1375);
FORCEPROP 1 LAST COMMENT_BODY TRUE
J 2
(-1080 1405);
DISPLAY 0.872340 (-1080 1405);
PAINT GREEN (-1080 1405);
DISPLAY INVISIBLE (-1080 1405);
FORCEPROP 2 LAST PATH I16
J 0
(-1400 1550);
DISPLAY 0.680851 (-1400 1550);
DISPLAY INVISIBLE (-1400 1550);
FORCEADD OFFPAGE..5
(-1125 1450);
FORCEPROP 2 LAST $XR0 297 
J 0
(-1410 1450);
DISPLAY 0.638298 (-1410 1450);
PAINT MONO (-1410 1450);
FORCEPROP 2 LAST CDS_LIB standard
J 0
(-1125 1450);
DISPLAY INVISIBLE (-1125 1450);
FORCEPROP 1 LAST OFFPAGE TRUE
J 0
(-800 1325);
DISPLAY 0.872340 (-800 1325);
PAINT AQUA (-800 1325);
DISPLAY INVISIBLE (-800 1325);
FORCEPROP 1 LAST COMMENT_BODY TRUE
J 0
(-1025 1375);
DISPLAY 1.170213 (-1025 1375);
PAINT GREEN (-1025 1375);
DISPLAY INVISIBLE (-1025 1375);
FORCEPROP 2 LAST PATH I17
J 0
(-1400 1500);
DISPLAY 0.680851 (-1400 1500);
DISPLAY INVISIBLE (-1400 1500);
FORCEADD OFFPAGE..2
R 2
(-1125 1350);
FORCEPROP 2 LAST $XR0 308 
J 0
(-1410 1350);
DISPLAY 0.638298 (-1410 1350);
PAINT MONO (-1410 1350);
FORCEPROP 2 LAST CDS_LIB standard
J 0
(-1125 1350);
DISPLAY INVISIBLE (-1125 1350);
FORCEPROP 1 LAST OFFPAGE TRUE
J 2
(-1450 1225);
DISPLAY 0.872340 (-1450 1225);
PAINT AQUA (-1450 1225);
DISPLAY INVISIBLE (-1450 1225);
FORCEPROP 1 LAST COMMENT_BODY TRUE
J 2
(-1080 1255);
DISPLAY 0.872340 (-1080 1255);
PAINT GREEN (-1080 1255);
DISPLAY INVISIBLE (-1080 1255);
FORCEPROP 2 LAST PATH I18
J 0
(-1400 1400);
DISPLAY 0.680851 (-1400 1400);
DISPLAY INVISIBLE (-1400 1400);
FORCEADD UNIVERSAL_GND..1
(-25 -250);
FORCEPROP 3 LASTPIN (-25 -200) SIG_NAME GND\g
J 0
(-15 -190);
DISPLAY 0.659574 (-15 -190);
PAINT MONO (-15 -190);
DISPLAY INVISIBLE (-15 -190);
FORCEPROP 2 LAST CDS_LIB pure_quanta_power
J 0
(-25 -250);
DISPLAY INVISIBLE (-25 -250);
FORCEPROP 1 LAST HDL_POWER GND
J 1
(0 -325);
DISPLAY 0.872340 (0 -325);
PAINT GREEN (0 -325);
DISPLAY INVISIBLE (0 -325);
FORCEPROP 1 LAST PATH I19
J 0
(50 -250);
DISPLAY 0.872340 (50 -250);
PAINT AQUA (50 -250);
DISPLAY INVISIBLE (50 -250);
FORCEADD OFFPAGE..1
(-1125 150);
FORCEPROP 2 LAST $XR0 309 
J 0
(-1377 150);
DISPLAY 0.638298 (-1377 150);
PAINT MONO (-1377 150);
FORCEPROP 2 LAST CDS_LIB standard
J 0
(-1125 150);
DISPLAY INVISIBLE (-1125 150);
FORCEPROP 1 LAST OFFPAGE TRUE
J 0
(-800 25);
DISPLAY 0.872340 (-800 25);
PAINT AQUA (-800 25);
DISPLAY INVISIBLE (-800 25);
FORCEPROP 1 LAST COMMENT_BODY TRUE
J 0
(-1000 50);
DISPLAY 0.872340 (-1000 50);
PAINT GREEN (-1000 50);
DISPLAY INVISIBLE (-1000 50);
FORCEPROP 2 LAST PATH I2
J 0
(-1375 200);
DISPLAY 0.680851 (-1375 200);
DISPLAY INVISIBLE (-1375 200);
FORCEADD OFFPAGE..1
(-1125 1750);
FORCEPROP 2 LAST $XR0 309 
J 0
(-1377 1750);
DISPLAY 0.638298 (-1377 1750);
PAINT MONO (-1377 1750);
FORCEPROP 2 LAST CDS_LIB standard
J 0
(-1125 1750);
DISPLAY INVISIBLE (-1125 1750);
FORCEPROP 1 LAST OFFPAGE TRUE
J 0
(-800 1625);
DISPLAY 0.872340 (-800 1625);
PAINT AQUA (-800 1625);
DISPLAY INVISIBLE (-800 1625);
FORCEPROP 1 LAST COMMENT_BODY TRUE
J 0
(-1000 1650);
DISPLAY 0.872340 (-1000 1650);
PAINT GREEN (-1000 1650);
DISPLAY INVISIBLE (-1000 1650);
FORCEPROP 2 LAST PATH I20
J 0
(-1375 1800);
DISPLAY 0.680851 (-1375 1800);
DISPLAY INVISIBLE (-1375 1800);
FORCEADD OFFPAGE..1
(-1125 1800);
FORCEPROP 2 LAST $XR0 309 
J 0
(-1377 1800);
DISPLAY 0.638298 (-1377 1800);
PAINT MONO (-1377 1800);
FORCEPROP 2 LAST CDS_LIB standard
J 0
(-1125 1800);
DISPLAY INVISIBLE (-1125 1800);
FORCEPROP 1 LAST OFFPAGE TRUE
J 0
(-800 1675);
DISPLAY 0.872340 (-800 1675);
PAINT AQUA (-800 1675);
DISPLAY INVISIBLE (-800 1675);
FORCEPROP 1 LAST COMMENT_BODY TRUE
J 0
(-1000 1700);
DISPLAY 0.872340 (-1000 1700);
PAINT GREEN (-1000 1700);
DISPLAY INVISIBLE (-1000 1700);
FORCEPROP 2 LAST PATH I21
J 0
(-1375 1850);
DISPLAY 0.680851 (-1375 1850);
DISPLAY INVISIBLE (-1375 1850);
FORCEADD OFFPAGE..1
(-1125 1900);
FORCEPROP 2 LAST $XR0 298 
J 0
(-1377 1900);
DISPLAY 0.638298 (-1377 1900);
PAINT MONO (-1377 1900);
FORCEPROP 2 LAST CDS_LIB standard
J 0
(-1125 1900);
DISPLAY INVISIBLE (-1125 1900);
FORCEPROP 1 LAST OFFPAGE TRUE
J 0
(-800 1775);
DISPLAY 0.872340 (-800 1775);
PAINT AQUA (-800 1775);
DISPLAY INVISIBLE (-800 1775);
FORCEPROP 1 LAST COMMENT_BODY TRUE
J 0
(-1000 1800);
DISPLAY 0.872340 (-1000 1800);
PAINT GREEN (-1000 1800);
DISPLAY INVISIBLE (-1000 1800);
FORCEPROP 2 LAST PATH I22
J 0
(-1375 1925);
DISPLAY 0.680851 (-1375 1925);
DISPLAY INVISIBLE (-1375 1925);
FORCEADD OFFPAGE..1
(-1125 1950);
FORCEPROP 2 LAST $XR0 298 
J 0
(-1377 1950);
DISPLAY 0.638298 (-1377 1950);
PAINT MONO (-1377 1950);
FORCEPROP 2 LAST CDS_LIB standard
J 0
(-1125 1950);
DISPLAY INVISIBLE (-1125 1950);
FORCEPROP 1 LAST OFFPAGE TRUE
J 0
(-800 1825);
DISPLAY 0.872340 (-800 1825);
PAINT AQUA (-800 1825);
DISPLAY INVISIBLE (-800 1825);
FORCEPROP 1 LAST COMMENT_BODY TRUE
J 0
(-1000 1850);
DISPLAY 0.872340 (-1000 1850);
PAINT GREEN (-1000 1850);
DISPLAY INVISIBLE (-1000 1850);
FORCEPROP 2 LAST PATH I23
J 0
(-1375 2000);
DISPLAY 0.680851 (-1375 2000);
DISPLAY INVISIBLE (-1375 2000);
FORCEADD OFFPAGE..5
(-1125 2050);
FORCEPROP 2 LAST $XR0 308 
J 0
(-1410 2050);
DISPLAY 0.638298 (-1410 2050);
PAINT MONO (-1410 2050);
FORCEPROP 2 LAST CDS_LIB standard
J 0
(-1125 2050);
DISPLAY INVISIBLE (-1125 2050);
FORCEPROP 1 LAST OFFPAGE TRUE
J 0
(-800 1925);
DISPLAY 0.872340 (-800 1925);
PAINT AQUA (-800 1925);
DISPLAY INVISIBLE (-800 1925);
FORCEPROP 1 LAST COMMENT_BODY TRUE
J 0
(-1025 1975);
DISPLAY 1.170213 (-1025 1975);
PAINT GREEN (-1025 1975);
DISPLAY INVISIBLE (-1025 1975);
FORCEPROP 2 LAST PATH I24
J 0
(-1400 2100);
DISPLAY 0.680851 (-1400 2100);
DISPLAY INVISIBLE (-1400 2100);
FORCEADD OFFPAGE..5
(-1125 2200);
FORCEPROP 2 LAST $XR0 297 
J 0
(-1410 2200);
DISPLAY 0.638298 (-1410 2200);
PAINT MONO (-1410 2200);
FORCEPROP 2 LAST CDS_LIB standard
J 0
(-1125 2200);
DISPLAY INVISIBLE (-1125 2200);
FORCEPROP 1 LAST OFFPAGE TRUE
J 0
(-800 2075);
DISPLAY 0.872340 (-800 2075);
PAINT AQUA (-800 2075);
DISPLAY INVISIBLE (-800 2075);
FORCEPROP 1 LAST COMMENT_BODY TRUE
J 0
(-1025 2125);
DISPLAY 1.170213 (-1025 2125);
PAINT GREEN (-1025 2125);
DISPLAY INVISIBLE (-1025 2125);
FORCEPROP 2 LAST PATH I25
J 0
(-1400 2250);
DISPLAY 0.680851 (-1400 2250);
DISPLAY INVISIBLE (-1400 2250);
FORCEADD OFFPAGE..2
R 2
(-1125 2250);
FORCEPROP 2 LAST $XR0 297 
J 0
(-1410 2250);
DISPLAY 0.638298 (-1410 2250);
PAINT MONO (-1410 2250);
FORCEPROP 2 LAST CDS_LIB standard
J 0
(-1125 2250);
DISPLAY INVISIBLE (-1125 2250);
FORCEPROP 1 LAST OFFPAGE TRUE
J 2
(-1450 2125);
DISPLAY 0.872340 (-1450 2125);
PAINT AQUA (-1450 2125);
DISPLAY INVISIBLE (-1450 2125);
FORCEPROP 1 LAST COMMENT_BODY TRUE
J 2
(-1080 2155);
DISPLAY 0.872340 (-1080 2155);
PAINT GREEN (-1080 2155);
DISPLAY INVISIBLE (-1080 2155);
FORCEPROP 2 LAST PATH I26
J 0
(-1400 2300);
DISPLAY 0.680851 (-1400 2300);
DISPLAY INVISIBLE (-1400 2300);
FORCEADD OFFPAGE..2
R 2
(-1125 2100);
FORCEPROP 2 LAST $XR0 308 
J 0
(-1410 2100);
DISPLAY 0.638298 (-1410 2100);
PAINT MONO (-1410 2100);
FORCEPROP 2 LAST CDS_LIB standard
J 0
(-1125 2100);
DISPLAY INVISIBLE (-1125 2100);
FORCEPROP 1 LAST OFFPAGE TRUE
J 2
(-1450 1975);
DISPLAY 0.872340 (-1450 1975);
PAINT AQUA (-1450 1975);
DISPLAY INVISIBLE (-1450 1975);
FORCEPROP 1 LAST COMMENT_BODY TRUE
J 2
(-1080 2005);
DISPLAY 0.872340 (-1080 2005);
PAINT GREEN (-1080 2005);
DISPLAY INVISIBLE (-1080 2005);
FORCEPROP 2 LAST PATH I27
J 0
(-1400 2150);
DISPLAY 0.680851 (-1400 2150);
DISPLAY INVISIBLE (-1400 2150);
FORCEADD OFFPAGE..2
R 2
(-1125 2350);
FORCEPROP 2 LAST $XR0 124 
J 0
(-1410 2350);
DISPLAY 0.638298 (-1410 2350);
PAINT MONO (-1410 2350);
FORCEPROP 2 LAST CDS_LIB standard
J 0
(-1125 2350);
DISPLAY INVISIBLE (-1125 2350);
FORCEPROP 1 LAST OFFPAGE TRUE
J 2
(-1450 2225);
DISPLAY 0.872340 (-1450 2225);
PAINT AQUA (-1450 2225);
DISPLAY INVISIBLE (-1450 2225);
FORCEPROP 1 LAST COMMENT_BODY TRUE
J 2
(-1080 2255);
DISPLAY 0.872340 (-1080 2255);
PAINT GREEN (-1080 2255);
DISPLAY INVISIBLE (-1080 2255);
FORCEPROP 2 LAST PATH I28
J 0
(-1400 2400);
DISPLAY 0.680851 (-1400 2400);
DISPLAY INVISIBLE (-1400 2400);
FORCEADD OFFPAGE..5
(-1125 2500);
FORCEPROP 2 LAST $XR0 127 
J 0
(-1410 2500);
DISPLAY 0.638298 (-1410 2500);
PAINT MONO (-1410 2500);
FORCEPROP 2 LAST CDS_LIB standard
J 0
(-1125 2500);
DISPLAY INVISIBLE (-1125 2500);
FORCEPROP 1 LAST OFFPAGE TRUE
J 0
(-800 2375);
DISPLAY 0.872340 (-800 2375);
PAINT AQUA (-800 2375);
DISPLAY INVISIBLE (-800 2375);
FORCEPROP 1 LAST COMMENT_BODY TRUE
J 0
(-1025 2425);
DISPLAY 1.170213 (-1025 2425);
PAINT GREEN (-1025 2425);
DISPLAY INVISIBLE (-1025 2425);
FORCEPROP 2 LAST PATH I29
J 0
(-1400 2550);
DISPLAY 0.680851 (-1400 2550);
DISPLAY INVISIBLE (-1400 2550);
FORCEADD OFFPAGE..5
(-1125 450);
FORCEPROP 2 LAST $XR0 308 
J 0
(-1410 450);
DISPLAY 0.638298 (-1410 450);
PAINT MONO (-1410 450);
FORCEPROP 2 LAST CDS_LIB standard
J 0
(-1125 450);
DISPLAY INVISIBLE (-1125 450);
FORCEPROP 1 LAST OFFPAGE TRUE
J 0
(-800 325);
DISPLAY 0.872340 (-800 325);
PAINT AQUA (-800 325);
DISPLAY INVISIBLE (-800 325);
FORCEPROP 1 LAST COMMENT_BODY TRUE
J 0
(-1025 375);
DISPLAY 1.170213 (-1025 375);
PAINT GREEN (-1025 375);
DISPLAY INVISIBLE (-1025 375);
FORCEPROP 2 LAST PATH I3
J 0
(-1400 500);
DISPLAY 0.680851 (-1400 500);
DISPLAY INVISIBLE (-1400 500);
FORCEADD OFFPAGE..1
(-1125 2600);
FORCEPROP 2 LAST $XR0 309 
J 0
(-1377 2600);
DISPLAY 0.638298 (-1377 2600);
PAINT MONO (-1377 2600);
FORCEPROP 2 LAST CDS_LIB standard
J 0
(-1125 2600);
DISPLAY INVISIBLE (-1125 2600);
FORCEPROP 1 LAST OFFPAGE TRUE
J 0
(-800 2475);
DISPLAY 0.872340 (-800 2475);
PAINT AQUA (-800 2475);
DISPLAY INVISIBLE (-800 2475);
FORCEPROP 1 LAST COMMENT_BODY TRUE
J 0
(-1000 2500);
DISPLAY 0.872340 (-1000 2500);
PAINT GREEN (-1000 2500);
DISPLAY INVISIBLE (-1000 2500);
FORCEPROP 2 LAST PATH I30
J 0
(-1375 2650);
DISPLAY 0.680851 (-1375 2650);
DISPLAY INVISIBLE (-1375 2650);
FORCEADD OFFPAGE..1
(-1125 2650);
FORCEPROP 2 LAST $XR0 309 
J 0
(-1377 2650);
DISPLAY 0.638298 (-1377 2650);
PAINT MONO (-1377 2650);
FORCEPROP 2 LAST CDS_LIB standard
J 0
(-1125 2650);
DISPLAY INVISIBLE (-1125 2650);
FORCEPROP 1 LAST OFFPAGE TRUE
J 0
(-800 2525);
DISPLAY 0.872340 (-800 2525);
PAINT AQUA (-800 2525);
DISPLAY INVISIBLE (-800 2525);
FORCEPROP 1 LAST COMMENT_BODY TRUE
J 0
(-1000 2550);
DISPLAY 0.872340 (-1000 2550);
PAINT GREEN (-1000 2550);
DISPLAY INVISIBLE (-1000 2550);
FORCEPROP 2 LAST PATH I31
J 0
(-1375 2700);
DISPLAY 0.680851 (-1375 2700);
DISPLAY INVISIBLE (-1375 2700);
FORCEADD OFFPAGE..1
(-1125 2750);
FORCEPROP 2 LAST $XR0 298 
J 0
(-1377 2750);
DISPLAY 0.638298 (-1377 2750);
PAINT MONO (-1377 2750);
FORCEPROP 2 LAST CDS_LIB standard
J 0
(-1125 2750);
DISPLAY INVISIBLE (-1125 2750);
FORCEPROP 1 LAST OFFPAGE TRUE
J 0
(-800 2625);
DISPLAY 0.872340 (-800 2625);
PAINT AQUA (-800 2625);
DISPLAY INVISIBLE (-800 2625);
FORCEPROP 1 LAST COMMENT_BODY TRUE
J 0
(-1000 2650);
DISPLAY 0.872340 (-1000 2650);
PAINT GREEN (-1000 2650);
DISPLAY INVISIBLE (-1000 2650);
FORCEPROP 2 LAST PATH I32
J 0
(-1375 2800);
DISPLAY 0.680851 (-1375 2800);
DISPLAY INVISIBLE (-1375 2800);
FORCEADD OFFPAGE..1
(-1125 2800);
FORCEPROP 2 LAST $XR0 298 
J 0
(-1377 2800);
DISPLAY 0.638298 (-1377 2800);
PAINT MONO (-1377 2800);
FORCEPROP 2 LAST CDS_LIB standard
J 0
(-1125 2800);
DISPLAY INVISIBLE (-1125 2800);
FORCEPROP 1 LAST OFFPAGE TRUE
J 0
(-800 2675);
DISPLAY 0.872340 (-800 2675);
PAINT AQUA (-800 2675);
DISPLAY INVISIBLE (-800 2675);
FORCEPROP 1 LAST COMMENT_BODY TRUE
J 0
(-1000 2700);
DISPLAY 0.872340 (-1000 2700);
PAINT GREEN (-1000 2700);
DISPLAY INVISIBLE (-1000 2700);
FORCEPROP 2 LAST PATH I33
J 0
(-1375 2850);
DISPLAY 0.680851 (-1375 2850);
DISPLAY INVISIBLE (-1375 2850);
FORCEADD OFFPAGE..5
(-1125 3050);
FORCEPROP 2 LAST $XR0 297 
J 0
(-1410 3050);
DISPLAY 0.638298 (-1410 3050);
PAINT MONO (-1410 3050);
FORCEPROP 2 LAST CDS_LIB standard
J 0
(-1125 3050);
DISPLAY INVISIBLE (-1125 3050);
FORCEPROP 1 LAST OFFPAGE TRUE
J 0
(-800 2925);
DISPLAY 0.872340 (-800 2925);
PAINT AQUA (-800 2925);
DISPLAY INVISIBLE (-800 2925);
FORCEPROP 1 LAST COMMENT_BODY TRUE
J 0
(-1025 2975);
DISPLAY 1.170213 (-1025 2975);
PAINT GREEN (-1025 2975);
DISPLAY INVISIBLE (-1025 2975);
FORCEPROP 2 LAST PATH I34
J 0
(-1400 3100);
DISPLAY 0.680851 (-1400 3100);
DISPLAY INVISIBLE (-1400 3100);
FORCEADD OFFPAGE..2
R 2
(-1125 2950);
FORCEPROP 2 LAST $XR0 308 
J 0
(-1410 2950);
DISPLAY 0.638298 (-1410 2950);
PAINT MONO (-1410 2950);
FORCEPROP 2 LAST CDS_LIB standard
J 0
(-1125 2950);
DISPLAY INVISIBLE (-1125 2950);
FORCEPROP 1 LAST OFFPAGE TRUE
J 2
(-1450 2825);
DISPLAY 0.872340 (-1450 2825);
PAINT AQUA (-1450 2825);
DISPLAY INVISIBLE (-1450 2825);
FORCEPROP 1 LAST COMMENT_BODY TRUE
J 2
(-1080 2855);
DISPLAY 0.872340 (-1080 2855);
PAINT GREEN (-1080 2855);
DISPLAY INVISIBLE (-1080 2855);
FORCEPROP 2 LAST PATH I35
J 0
(-1400 3000);
DISPLAY 0.680851 (-1400 3000);
DISPLAY INVISIBLE (-1400 3000);
FORCEADD OFFPAGE..5
(-1125 2900);
FORCEPROP 2 LAST $XR0 308 
J 0
(-1410 2900);
DISPLAY 0.638298 (-1410 2900);
PAINT MONO (-1410 2900);
FORCEPROP 2 LAST CDS_LIB standard
J 0
(-1125 2900);
DISPLAY INVISIBLE (-1125 2900);
FORCEPROP 1 LAST OFFPAGE TRUE
J 0
(-800 2775);
DISPLAY 0.872340 (-800 2775);
PAINT AQUA (-800 2775);
DISPLAY INVISIBLE (-800 2775);
FORCEPROP 1 LAST COMMENT_BODY TRUE
J 0
(-1025 2825);
DISPLAY 1.170213 (-1025 2825);
PAINT GREEN (-1025 2825);
DISPLAY INVISIBLE (-1025 2825);
FORCEPROP 2 LAST PATH I36
J 0
(-1400 2950);
DISPLAY 0.680851 (-1400 2950);
DISPLAY INVISIBLE (-1400 2950);
FORCEADD OFFPAGE..2
R 2
(-1125 3100);
FORCEPROP 2 LAST $XR0 297 
J 0
(-1410 3100);
DISPLAY 0.638298 (-1410 3100);
PAINT MONO (-1410 3100);
FORCEPROP 2 LAST CDS_LIB standard
J 0
(-1125 3100);
DISPLAY INVISIBLE (-1125 3100);
FORCEPROP 1 LAST OFFPAGE TRUE
J 2
(-1450 2975);
DISPLAY 0.872340 (-1450 2975);
PAINT AQUA (-1450 2975);
DISPLAY INVISIBLE (-1450 2975);
FORCEPROP 1 LAST COMMENT_BODY TRUE
J 2
(-1080 3005);
DISPLAY 0.872340 (-1080 3005);
PAINT GREEN (-1080 3005);
DISPLAY INVISIBLE (-1080 3005);
FORCEPROP 2 LAST PATH I37
J 0
(-1400 3150);
DISPLAY 0.680851 (-1400 3150);
DISPLAY INVISIBLE (-1400 3150);
FORCEADD OFFPAGE..1
(3800 200);
FORCEPROP 2 LAST $XR0 309 
J 0
(3548 200);
DISPLAY 0.638298 (3548 200);
PAINT MONO (3548 200);
FORCEPROP 2 LAST CDS_LIB standard
J 0
(3800 200);
DISPLAY INVISIBLE (3800 200);
FORCEPROP 1 LAST OFFPAGE TRUE
J 0
(4125 75);
DISPLAY 0.872340 (4125 75);
PAINT AQUA (4125 75);
DISPLAY INVISIBLE (4125 75);
FORCEPROP 1 LAST COMMENT_BODY TRUE
J 0
(3925 100);
DISPLAY 0.872340 (3925 100);
PAINT GREEN (3925 100);
DISPLAY INVISIBLE (3925 100);
FORCEPROP 2 LAST PATH I38
J 0
(3550 250);
DISPLAY 0.680851 (3550 250);
DISPLAY INVISIBLE (3550 250);
FORCEADD OFFPAGE..1
(3800 150);
FORCEPROP 2 LAST $XR0 309 
J 0
(3548 150);
DISPLAY 0.638298 (3548 150);
PAINT MONO (3548 150);
FORCEPROP 2 LAST CDS_LIB standard
J 0
(3800 150);
DISPLAY INVISIBLE (3800 150);
FORCEPROP 1 LAST OFFPAGE TRUE
J 0
(4125 25);
DISPLAY 0.872340 (4125 25);
PAINT AQUA (4125 25);
DISPLAY INVISIBLE (4125 25);
FORCEPROP 1 LAST COMMENT_BODY TRUE
J 0
(3925 50);
DISPLAY 0.872340 (3925 50);
PAINT GREEN (3925 50);
DISPLAY INVISIBLE (3925 50);
FORCEPROP 2 LAST PATH I39
J 0
(3550 200);
DISPLAY 0.680851 (3550 200);
DISPLAY INVISIBLE (3550 200);
FORCEADD OFFPAGE..2
R 2
(-1125 500);
FORCEPROP 2 LAST $XR0 308 
J 0
(-1410 500);
DISPLAY 0.638298 (-1410 500);
PAINT MONO (-1410 500);
FORCEPROP 2 LAST CDS_LIB standard
J 0
(-1125 500);
DISPLAY INVISIBLE (-1125 500);
FORCEPROP 1 LAST OFFPAGE TRUE
J 2
(-1450 375);
DISPLAY 0.872340 (-1450 375);
PAINT AQUA (-1450 375);
DISPLAY INVISIBLE (-1450 375);
FORCEPROP 1 LAST COMMENT_BODY TRUE
J 2
(-1080 405);
DISPLAY 0.872340 (-1080 405);
PAINT GREEN (-1080 405);
DISPLAY INVISIBLE (-1080 405);
FORCEPROP 2 LAST PATH I4
J 0
(-1400 550);
DISPLAY 0.680851 (-1400 550);
DISPLAY INVISIBLE (-1400 550);
FORCEADD OFFPAGE..1
(3800 300);
FORCEPROP 2 LAST $XR0 298 
J 0
(3548 300);
DISPLAY 0.638298 (3548 300);
PAINT MONO (3548 300);
FORCEPROP 2 LAST CDS_LIB standard
J 0
(3800 300);
DISPLAY INVISIBLE (3800 300);
FORCEPROP 1 LAST OFFPAGE TRUE
J 0
(4125 175);
DISPLAY 0.872340 (4125 175);
PAINT AQUA (4125 175);
DISPLAY INVISIBLE (4125 175);
FORCEPROP 1 LAST COMMENT_BODY TRUE
J 0
(3925 200);
DISPLAY 0.872340 (3925 200);
PAINT GREEN (3925 200);
DISPLAY INVISIBLE (3925 200);
FORCEPROP 2 LAST PATH I40
J 0
(3550 350);
DISPLAY 0.680851 (3550 350);
DISPLAY INVISIBLE (3550 350);
FORCEADD OFFPAGE..1
(3800 350);
FORCEPROP 2 LAST $XR0 298 
J 0
(3548 350);
DISPLAY 0.638298 (3548 350);
PAINT MONO (3548 350);
FORCEPROP 2 LAST CDS_LIB standard
J 0
(3800 350);
DISPLAY INVISIBLE (3800 350);
FORCEPROP 1 LAST OFFPAGE TRUE
J 0
(4125 225);
DISPLAY 0.872340 (4125 225);
PAINT AQUA (4125 225);
DISPLAY INVISIBLE (4125 225);
FORCEPROP 1 LAST COMMENT_BODY TRUE
J 0
(3925 250);
DISPLAY 0.872340 (3925 250);
PAINT GREEN (3925 250);
DISPLAY INVISIBLE (3925 250);
FORCEPROP 2 LAST PATH I41
J 0
(3550 400);
DISPLAY 0.680851 (3550 400);
DISPLAY INVISIBLE (3550 400);
FORCEADD OFFPAGE..5
(3800 450);
FORCEPROP 2 LAST $XR0 308 
J 0
(3545 450);
DISPLAY 0.638298 (3545 450);
PAINT MONO (3545 450);
FORCEPROP 2 LAST CDS_LIB standard
J 0
(3800 450);
DISPLAY INVISIBLE (3800 450);
FORCEPROP 1 LAST OFFPAGE TRUE
J 0
(4125 325);
DISPLAY 0.872340 (4125 325);
PAINT AQUA (4125 325);
DISPLAY INVISIBLE (4125 325);
FORCEPROP 1 LAST COMMENT_BODY TRUE
J 0
(3900 375);
DISPLAY 1.170213 (3900 375);
PAINT GREEN (3900 375);
DISPLAY INVISIBLE (3900 375);
FORCEPROP 2 LAST PATH I42
J 0
(3550 500);
DISPLAY 0.680851 (3550 500);
DISPLAY INVISIBLE (3550 500);
FORCEADD OFFPAGE..2
R 2
(3800 500);
FORCEPROP 2 LAST $XR0 308 
J 0
(3545 500);
DISPLAY 0.638298 (3545 500);
PAINT MONO (3545 500);
FORCEPROP 2 LAST CDS_LIB standard
J 0
(3800 500);
DISPLAY INVISIBLE (3800 500);
FORCEPROP 1 LAST OFFPAGE TRUE
J 2
(3475 375);
DISPLAY 0.872340 (3475 375);
PAINT AQUA (3475 375);
DISPLAY INVISIBLE (3475 375);
FORCEPROP 1 LAST COMMENT_BODY TRUE
J 2
(3845 405);
DISPLAY 0.872340 (3845 405);
PAINT GREEN (3845 405);
DISPLAY INVISIBLE (3845 405);
FORCEPROP 2 LAST PATH I43
J 0
(3550 550);
DISPLAY 0.680851 (3550 550);
DISPLAY INVISIBLE (3550 550);
FORCEADD OFFPAGE..2
R 2
(3800 650);
FORCEPROP 2 LAST $XR0 297 
J 0
(3545 650);
DISPLAY 0.638298 (3545 650);
PAINT MONO (3545 650);
FORCEPROP 2 LAST CDS_LIB standard
J 0
(3800 650);
DISPLAY INVISIBLE (3800 650);
FORCEPROP 1 LAST OFFPAGE TRUE
J 2
(3475 525);
DISPLAY 0.872340 (3475 525);
PAINT AQUA (3475 525);
DISPLAY INVISIBLE (3475 525);
FORCEPROP 1 LAST COMMENT_BODY TRUE
J 2
(3845 555);
DISPLAY 0.872340 (3845 555);
PAINT GREEN (3845 555);
DISPLAY INVISIBLE (3845 555);
FORCEPROP 2 LAST PATH I44
J 0
(3550 700);
DISPLAY 0.680851 (3550 700);
DISPLAY INVISIBLE (3550 700);
FORCEADD OFFPAGE..5
(3800 600);
FORCEPROP 2 LAST $XR0 297 
J 0
(3545 600);
DISPLAY 0.638298 (3545 600);
PAINT MONO (3545 600);
FORCEPROP 2 LAST CDS_LIB standard
J 0
(3800 600);
DISPLAY INVISIBLE (3800 600);
FORCEPROP 1 LAST OFFPAGE TRUE
J 0
(4125 475);
DISPLAY 0.872340 (4125 475);
PAINT AQUA (4125 475);
DISPLAY INVISIBLE (4125 475);
FORCEPROP 1 LAST COMMENT_BODY TRUE
J 0
(3900 525);
DISPLAY 1.170213 (3900 525);
PAINT GREEN (3900 525);
DISPLAY INVISIBLE (3900 525);
FORCEPROP 2 LAST PATH I45
J 0
(3550 650);
DISPLAY 0.680851 (3550 650);
DISPLAY INVISIBLE (3550 650);
FORCEADD OFFPAGE..2
R 2
(3800 750);
FORCEPROP 2 LAST $XR0 124 
J 0
(3545 750);
DISPLAY 0.638298 (3545 750);
PAINT MONO (3545 750);
FORCEPROP 2 LAST CDS_LIB standard
J 0
(3800 750);
DISPLAY INVISIBLE (3800 750);
FORCEPROP 1 LAST OFFPAGE TRUE
J 2
(3475 625);
DISPLAY 0.872340 (3475 625);
PAINT AQUA (3475 625);
DISPLAY INVISIBLE (3475 625);
FORCEPROP 1 LAST COMMENT_BODY TRUE
J 2
(3845 655);
DISPLAY 0.872340 (3845 655);
PAINT GREEN (3845 655);
DISPLAY INVISIBLE (3845 655);
FORCEPROP 2 LAST PATH I46
J 0
(3550 800);
DISPLAY 0.680851 (3550 800);
DISPLAY INVISIBLE (3550 800);
FORCEADD OFFPAGE..1
(3800 1000);
FORCEPROP 2 LAST $XR0 309 
J 0
(3548 1000);
DISPLAY 0.638298 (3548 1000);
PAINT MONO (3548 1000);
FORCEPROP 2 LAST CDS_LIB standard
J 0
(3800 1000);
DISPLAY INVISIBLE (3800 1000);
FORCEPROP 1 LAST OFFPAGE TRUE
J 0
(4125 875);
DISPLAY 0.872340 (4125 875);
PAINT AQUA (4125 875);
DISPLAY INVISIBLE (4125 875);
FORCEPROP 1 LAST COMMENT_BODY TRUE
J 0
(3925 900);
DISPLAY 0.872340 (3925 900);
PAINT GREEN (3925 900);
DISPLAY INVISIBLE (3925 900);
FORCEPROP 2 LAST PATH I47
J 0
(3550 1050);
DISPLAY 0.680851 (3550 1050);
DISPLAY INVISIBLE (3550 1050);
FORCEADD OFFPAGE..4
R 2
(3800 900);
FORCEPROP 2 LAST $XR0 128 
J 0
(3548 900);
DISPLAY 0.638298 (3548 900);
PAINT MONO (3548 900);
FORCEPROP 2 LAST CDS_LIB standard
J 0
(3800 900);
DISPLAY INVISIBLE (3800 900);
FORCEPROP 1 LAST OFFPAGE TRUE
J 2
(3475 775);
DISPLAY 0.872340 (3475 775);
PAINT GREEN (3475 775);
DISPLAY INVISIBLE (3475 775);
FORCEPROP 1 LAST COMMENT_BODY TRUE
J 2
(3825 800);
DISPLAY 0.872340 (3825 800);
PAINT GREEN (3825 800);
DISPLAY INVISIBLE (3825 800);
FORCEPROP 2 LAST PATH I48
J 0
(3550 950);
DISPLAY 0.680851 (3550 950);
DISPLAY INVISIBLE (3550 950);
FORCEADD OFFPAGE..1
(3800 1050);
FORCEPROP 2 LAST $XR0 309 
J 0
(3548 1050);
DISPLAY 0.638298 (3548 1050);
PAINT MONO (3548 1050);
FORCEPROP 2 LAST CDS_LIB standard
J 0
(3800 1050);
DISPLAY INVISIBLE (3800 1050);
FORCEPROP 1 LAST OFFPAGE TRUE
J 0
(4125 925);
DISPLAY 0.872340 (4125 925);
PAINT AQUA (4125 925);
DISPLAY INVISIBLE (4125 925);
FORCEPROP 1 LAST COMMENT_BODY TRUE
J 0
(3925 950);
DISPLAY 0.872340 (3925 950);
PAINT GREEN (3925 950);
DISPLAY INVISIBLE (3925 950);
FORCEPROP 2 LAST PATH I49
J 0
(3550 1100);
DISPLAY 0.680851 (3550 1100);
DISPLAY INVISIBLE (3550 1100);
FORCEADD OFFPAGE..1
(-1125 350);
FORCEPROP 2 LAST $XR0 298 
J 0
(-1377 350);
DISPLAY 0.638298 (-1377 350);
PAINT MONO (-1377 350);
FORCEPROP 2 LAST CDS_LIB standard
J 0
(-1125 350);
DISPLAY INVISIBLE (-1125 350);
FORCEPROP 1 LAST OFFPAGE TRUE
J 0
(-800 225);
DISPLAY 0.872340 (-800 225);
PAINT AQUA (-800 225);
DISPLAY INVISIBLE (-800 225);
FORCEPROP 1 LAST COMMENT_BODY TRUE
J 0
(-1000 250);
DISPLAY 0.872340 (-1000 250);
PAINT GREEN (-1000 250);
DISPLAY INVISIBLE (-1000 250);
FORCEPROP 2 LAST PATH I5
J 0
(-1400 400);
DISPLAY 0.680851 (-1400 400);
DISPLAY INVISIBLE (-1400 400);
FORCEADD OFFPAGE..1
(3800 1200);
FORCEPROP 2 LAST $XR0 298 
J 0
(3548 1200);
DISPLAY 0.638298 (3548 1200);
PAINT MONO (3548 1200);
FORCEPROP 2 LAST CDS_LIB standard
J 0
(3800 1200);
DISPLAY INVISIBLE (3800 1200);
FORCEPROP 1 LAST OFFPAGE TRUE
J 0
(4125 1075);
DISPLAY 0.872340 (4125 1075);
PAINT AQUA (4125 1075);
DISPLAY INVISIBLE (4125 1075);
FORCEPROP 1 LAST COMMENT_BODY TRUE
J 0
(3925 1100);
DISPLAY 0.872340 (3925 1100);
PAINT GREEN (3925 1100);
DISPLAY INVISIBLE (3925 1100);
FORCEPROP 2 LAST PATH I50
J 0
(3550 1250);
DISPLAY 0.680851 (3550 1250);
DISPLAY INVISIBLE (3550 1250);
FORCEADD OFFPAGE..1
(3800 1150);
FORCEPROP 2 LAST $XR0 298 
J 0
(3548 1150);
DISPLAY 0.638298 (3548 1150);
PAINT MONO (3548 1150);
FORCEPROP 2 LAST CDS_LIB standard
J 0
(3800 1150);
DISPLAY INVISIBLE (3800 1150);
FORCEPROP 1 LAST OFFPAGE TRUE
J 0
(4125 1025);
DISPLAY 0.872340 (4125 1025);
PAINT AQUA (4125 1025);
DISPLAY INVISIBLE (4125 1025);
FORCEPROP 1 LAST COMMENT_BODY TRUE
J 0
(3925 1050);
DISPLAY 0.872340 (3925 1050);
PAINT GREEN (3925 1050);
DISPLAY INVISIBLE (3925 1050);
FORCEPROP 2 LAST PATH I51
J 0
(3550 1200);
DISPLAY 0.680851 (3550 1200);
DISPLAY INVISIBLE (3550 1200);
FORCEADD OFFPAGE..5
(3800 1300);
FORCEPROP 2 LAST $XR0 308 
J 0
(3545 1300);
DISPLAY 0.638298 (3545 1300);
PAINT MONO (3545 1300);
FORCEPROP 2 LAST CDS_LIB standard
J 0
(3800 1300);
DISPLAY INVISIBLE (3800 1300);
FORCEPROP 1 LAST OFFPAGE TRUE
J 0
(4125 1175);
DISPLAY 0.872340 (4125 1175);
PAINT AQUA (4125 1175);
DISPLAY INVISIBLE (4125 1175);
FORCEPROP 1 LAST COMMENT_BODY TRUE
J 0
(3900 1225);
DISPLAY 1.170213 (3900 1225);
PAINT GREEN (3900 1225);
DISPLAY INVISIBLE (3900 1225);
FORCEPROP 2 LAST PATH I52
J 0
(3550 1350);
DISPLAY 0.680851 (3550 1350);
DISPLAY INVISIBLE (3550 1350);
FORCEADD OFFPAGE..2
R 2
(3800 1350);
FORCEPROP 2 LAST $XR0 308 
J 0
(3545 1350);
DISPLAY 0.638298 (3545 1350);
PAINT MONO (3545 1350);
FORCEPROP 2 LAST CDS_LIB standard
J 0
(3800 1350);
DISPLAY INVISIBLE (3800 1350);
FORCEPROP 1 LAST OFFPAGE TRUE
J 2
(3475 1225);
DISPLAY 0.872340 (3475 1225);
PAINT AQUA (3475 1225);
DISPLAY INVISIBLE (3475 1225);
FORCEPROP 1 LAST COMMENT_BODY TRUE
J 2
(3845 1255);
DISPLAY 0.872340 (3845 1255);
PAINT GREEN (3845 1255);
DISPLAY INVISIBLE (3845 1255);
FORCEPROP 2 LAST PATH I53
J 0
(3550 1400);
DISPLAY 0.680851 (3550 1400);
DISPLAY INVISIBLE (3550 1400);
FORCEADD OFFPAGE..5
(3800 1450);
FORCEPROP 2 LAST $XR0 297 
J 0
(3545 1450);
DISPLAY 0.638298 (3545 1450);
PAINT MONO (3545 1450);
FORCEPROP 2 LAST CDS_LIB standard
J 0
(3800 1450);
DISPLAY INVISIBLE (3800 1450);
FORCEPROP 1 LAST OFFPAGE TRUE
J 0
(4125 1325);
DISPLAY 0.872340 (4125 1325);
PAINT AQUA (4125 1325);
DISPLAY INVISIBLE (4125 1325);
FORCEPROP 1 LAST COMMENT_BODY TRUE
J 0
(3900 1375);
DISPLAY 1.170213 (3900 1375);
PAINT GREEN (3900 1375);
DISPLAY INVISIBLE (3900 1375);
FORCEPROP 2 LAST PATH I54
J 0
(3550 1500);
DISPLAY 0.680851 (3550 1500);
DISPLAY INVISIBLE (3550 1500);
FORCEADD OFFPAGE..2
R 2
(3800 1500);
FORCEPROP 2 LAST $XR0 297 
J 0
(3545 1500);
DISPLAY 0.638298 (3545 1500);
PAINT MONO (3545 1500);
FORCEPROP 2 LAST CDS_LIB standard
J 0
(3800 1500);
DISPLAY INVISIBLE (3800 1500);
FORCEPROP 1 LAST OFFPAGE TRUE
J 2
(3475 1375);
DISPLAY 0.872340 (3475 1375);
PAINT AQUA (3475 1375);
DISPLAY INVISIBLE (3475 1375);
FORCEPROP 1 LAST COMMENT_BODY TRUE
J 2
(3845 1405);
DISPLAY 0.872340 (3845 1405);
PAINT GREEN (3845 1405);
DISPLAY INVISIBLE (3845 1405);
FORCEPROP 2 LAST PATH I55
J 0
(3550 1550);
DISPLAY 0.680851 (3550 1550);
DISPLAY INVISIBLE (3550 1550);
FORCEADD OFFPAGE..1
(3775 1750);
FORCEPROP 2 LAST $XR0 309 
J 0
(3523 1750);
DISPLAY 0.638298 (3523 1750);
PAINT MONO (3523 1750);
FORCEPROP 2 LAST CDS_LIB standard
J 0
(3775 1750);
DISPLAY INVISIBLE (3775 1750);
FORCEPROP 1 LAST OFFPAGE TRUE
J 0
(4100 1625);
DISPLAY 0.872340 (4100 1625);
PAINT AQUA (4100 1625);
DISPLAY INVISIBLE (4100 1625);
FORCEPROP 1 LAST COMMENT_BODY TRUE
J 0
(3900 1650);
DISPLAY 0.872340 (3900 1650);
PAINT GREEN (3900 1650);
DISPLAY INVISIBLE (3900 1650);
FORCEPROP 2 LAST PATH I56
J 0
(3500 1800);
DISPLAY 0.680851 (3500 1800);
DISPLAY INVISIBLE (3500 1800);
FORCEADD OFFPAGE..1
(3775 1800);
FORCEPROP 2 LAST $XR0 309 
J 0
(3523 1800);
DISPLAY 0.638298 (3523 1800);
PAINT MONO (3523 1800);
FORCEPROP 2 LAST CDS_LIB standard
J 0
(3775 1800);
DISPLAY INVISIBLE (3775 1800);
FORCEPROP 1 LAST OFFPAGE TRUE
J 0
(4100 1675);
DISPLAY 0.872340 (4100 1675);
PAINT AQUA (4100 1675);
DISPLAY INVISIBLE (4100 1675);
FORCEPROP 1 LAST COMMENT_BODY TRUE
J 0
(3900 1700);
DISPLAY 0.872340 (3900 1700);
PAINT GREEN (3900 1700);
DISPLAY INVISIBLE (3900 1700);
FORCEPROP 2 LAST PATH I57
J 0
(3500 1850);
DISPLAY 0.680851 (3500 1850);
DISPLAY INVISIBLE (3500 1850);
FORCEADD OFFPAGE..5
(3775 2050);
FORCEPROP 2 LAST $XR0 308 
J 0
(3520 2050);
DISPLAY 0.638298 (3520 2050);
PAINT MONO (3520 2050);
FORCEPROP 2 LAST CDS_LIB standard
J 0
(3775 2050);
DISPLAY INVISIBLE (3775 2050);
FORCEPROP 1 LAST OFFPAGE TRUE
J 0
(4100 1925);
DISPLAY 0.872340 (4100 1925);
PAINT AQUA (4100 1925);
DISPLAY INVISIBLE (4100 1925);
FORCEPROP 1 LAST COMMENT_BODY TRUE
J 0
(3875 1975);
DISPLAY 1.170213 (3875 1975);
PAINT GREEN (3875 1975);
DISPLAY INVISIBLE (3875 1975);
FORCEPROP 2 LAST PATH I58
J 0
(3525 2100);
DISPLAY 0.680851 (3525 2100);
DISPLAY INVISIBLE (3525 2100);
FORCEADD OFFPAGE..1
(3775 1950);
FORCEPROP 2 LAST $XR0 298 
J 0
(3523 1950);
DISPLAY 0.638298 (3523 1950);
PAINT MONO (3523 1950);
FORCEPROP 2 LAST CDS_LIB standard
J 0
(3775 1950);
DISPLAY INVISIBLE (3775 1950);
FORCEPROP 1 LAST OFFPAGE TRUE
J 0
(4100 1825);
DISPLAY 0.872340 (4100 1825);
PAINT AQUA (4100 1825);
DISPLAY INVISIBLE (4100 1825);
FORCEPROP 1 LAST COMMENT_BODY TRUE
J 0
(3900 1850);
DISPLAY 0.872340 (3900 1850);
PAINT GREEN (3900 1850);
DISPLAY INVISIBLE (3900 1850);
FORCEPROP 2 LAST PATH I59
J 0
(3500 2000);
DISPLAY 0.680851 (3500 2000);
DISPLAY INVISIBLE (3500 2000);
FORCEADD OFFPAGE..1
(-1125 300);
FORCEPROP 2 LAST $XR0 298 
J 0
(-1377 300);
DISPLAY 0.638298 (-1377 300);
PAINT MONO (-1377 300);
FORCEPROP 2 LAST CDS_LIB standard
J 0
(-1125 300);
DISPLAY INVISIBLE (-1125 300);
FORCEPROP 1 LAST OFFPAGE TRUE
J 0
(-800 175);
DISPLAY 0.872340 (-800 175);
PAINT AQUA (-800 175);
DISPLAY INVISIBLE (-800 175);
FORCEPROP 1 LAST COMMENT_BODY TRUE
J 0
(-1000 200);
DISPLAY 0.872340 (-1000 200);
PAINT GREEN (-1000 200);
DISPLAY INVISIBLE (-1000 200);
FORCEPROP 2 LAST PATH I6
J 0
(-1400 350);
DISPLAY 0.680851 (-1400 350);
DISPLAY INVISIBLE (-1400 350);
FORCEADD OFFPAGE..1
(3775 1900);
FORCEPROP 2 LAST $XR0 298 
J 0
(3523 1900);
DISPLAY 0.638298 (3523 1900);
PAINT MONO (3523 1900);
FORCEPROP 2 LAST CDS_LIB standard
J 0
(3775 1900);
DISPLAY INVISIBLE (3775 1900);
FORCEPROP 1 LAST OFFPAGE TRUE
J 0
(4100 1775);
DISPLAY 0.872340 (4100 1775);
PAINT AQUA (4100 1775);
DISPLAY INVISIBLE (4100 1775);
FORCEPROP 1 LAST COMMENT_BODY TRUE
J 0
(3900 1800);
DISPLAY 0.872340 (3900 1800);
PAINT GREEN (3900 1800);
DISPLAY INVISIBLE (3900 1800);
FORCEPROP 2 LAST PATH I60
J 0
(3500 1950);
DISPLAY 0.680851 (3500 1950);
DISPLAY INVISIBLE (3500 1950);
FORCEADD OFFPAGE..2
R 2
(3775 2100);
FORCEPROP 2 LAST $XR0 308 
J 0
(3520 2100);
DISPLAY 0.638298 (3520 2100);
PAINT MONO (3520 2100);
FORCEPROP 2 LAST CDS_LIB standard
J 0
(3775 2100);
DISPLAY INVISIBLE (3775 2100);
FORCEPROP 1 LAST OFFPAGE TRUE
J 2
(3450 1975);
DISPLAY 0.872340 (3450 1975);
PAINT AQUA (3450 1975);
DISPLAY INVISIBLE (3450 1975);
FORCEPROP 1 LAST COMMENT_BODY TRUE
J 2
(3820 2005);
DISPLAY 0.872340 (3820 2005);
PAINT GREEN (3820 2005);
DISPLAY INVISIBLE (3820 2005);
FORCEPROP 2 LAST PATH I61
J 0
(3525 2150);
DISPLAY 0.680851 (3525 2150);
DISPLAY INVISIBLE (3525 2150);
FORCEADD OFFPAGE..5
(3775 2200);
FORCEPROP 2 LAST $XR0 297 
J 0
(3520 2200);
DISPLAY 0.638298 (3520 2200);
PAINT MONO (3520 2200);
FORCEPROP 2 LAST CDS_LIB standard
J 0
(3775 2200);
DISPLAY INVISIBLE (3775 2200);
FORCEPROP 1 LAST OFFPAGE TRUE
J 0
(4100 2075);
DISPLAY 0.872340 (4100 2075);
PAINT AQUA (4100 2075);
DISPLAY INVISIBLE (4100 2075);
FORCEPROP 1 LAST COMMENT_BODY TRUE
J 0
(3875 2125);
DISPLAY 1.170213 (3875 2125);
PAINT GREEN (3875 2125);
DISPLAY INVISIBLE (3875 2125);
FORCEPROP 2 LAST PATH I62
J 0
(3525 2250);
DISPLAY 0.680851 (3525 2250);
DISPLAY INVISIBLE (3525 2250);
FORCEADD OFFPAGE..2
R 2
(3775 2250);
FORCEPROP 2 LAST $XR0 297 
J 0
(3520 2250);
DISPLAY 0.638298 (3520 2250);
PAINT MONO (3520 2250);
FORCEPROP 2 LAST CDS_LIB standard
J 0
(3775 2250);
DISPLAY INVISIBLE (3775 2250);
FORCEPROP 1 LAST OFFPAGE TRUE
J 2
(3450 2125);
DISPLAY 0.872340 (3450 2125);
PAINT AQUA (3450 2125);
DISPLAY INVISIBLE (3450 2125);
FORCEPROP 1 LAST COMMENT_BODY TRUE
J 2
(3820 2155);
DISPLAY 0.872340 (3820 2155);
PAINT GREEN (3820 2155);
DISPLAY INVISIBLE (3820 2155);
FORCEPROP 2 LAST PATH I63
J 0
(3525 2300);
DISPLAY 0.680851 (3525 2300);
DISPLAY INVISIBLE (3525 2300);
FORCEADD OFFPAGE..5
(3775 2500);
FORCEPROP 2 LAST $XR0 127 
J 0
(3520 2500);
DISPLAY 0.638298 (3520 2500);
PAINT MONO (3520 2500);
FORCEPROP 2 LAST CDS_LIB standard
J 0
(3775 2500);
DISPLAY INVISIBLE (3775 2500);
FORCEPROP 1 LAST OFFPAGE TRUE
J 0
(4100 2375);
DISPLAY 0.872340 (4100 2375);
PAINT AQUA (4100 2375);
DISPLAY INVISIBLE (4100 2375);
FORCEPROP 1 LAST COMMENT_BODY TRUE
J 0
(3875 2425);
DISPLAY 1.170213 (3875 2425);
PAINT GREEN (3875 2425);
DISPLAY INVISIBLE (3875 2425);
FORCEPROP 2 LAST PATH I64
J 0
(3525 2550);
DISPLAY 0.680851 (3525 2550);
DISPLAY INVISIBLE (3525 2550);
FORCEADD OFFPAGE..1
(3775 2350);
FORCEPROP 2 LAST $XR0 126 
J 0
(3523 2350);
DISPLAY 0.638298 (3523 2350);
PAINT MONO (3523 2350);
FORCEPROP 2 LAST CDS_LIB standard
J 0
(3775 2350);
DISPLAY INVISIBLE (3775 2350);
FORCEPROP 1 LAST OFFPAGE TRUE
J 0
(4100 2225);
DISPLAY 0.872340 (4100 2225);
PAINT AQUA (4100 2225);
DISPLAY INVISIBLE (4100 2225);
FORCEPROP 1 LAST COMMENT_BODY TRUE
J 0
(3900 2250);
DISPLAY 0.872340 (3900 2250);
PAINT GREEN (3900 2250);
DISPLAY INVISIBLE (3900 2250);
FORCEPROP 2 LAST PATH I65
J 0
(3500 2400);
DISPLAY 0.680851 (3500 2400);
DISPLAY INVISIBLE (3500 2400);
FORCEADD OFFPAGE..1
(3775 2600);
FORCEPROP 2 LAST $XR0 309 
J 0
(3523 2600);
DISPLAY 0.638298 (3523 2600);
PAINT MONO (3523 2600);
FORCEPROP 2 LAST CDS_LIB standard
J 0
(3775 2600);
DISPLAY INVISIBLE (3775 2600);
FORCEPROP 1 LAST OFFPAGE TRUE
J 0
(4100 2475);
DISPLAY 0.872340 (4100 2475);
PAINT AQUA (4100 2475);
DISPLAY INVISIBLE (4100 2475);
FORCEPROP 1 LAST COMMENT_BODY TRUE
J 0
(3900 2500);
DISPLAY 0.872340 (3900 2500);
PAINT GREEN (3900 2500);
DISPLAY INVISIBLE (3900 2500);
FORCEPROP 2 LAST PATH I66
J 0
(3500 2650);
DISPLAY 0.680851 (3500 2650);
DISPLAY INVISIBLE (3500 2650);
FORCEADD OFFPAGE..1
(3775 2800);
FORCEPROP 2 LAST $XR0 298 
J 0
(3523 2800);
DISPLAY 0.638298 (3523 2800);
PAINT MONO (3523 2800);
FORCEPROP 2 LAST CDS_LIB standard
J 0
(3775 2800);
DISPLAY INVISIBLE (3775 2800);
FORCEPROP 1 LAST OFFPAGE TRUE
J 0
(4100 2675);
DISPLAY 0.872340 (4100 2675);
PAINT AQUA (4100 2675);
DISPLAY INVISIBLE (4100 2675);
FORCEPROP 1 LAST COMMENT_BODY TRUE
J 0
(3900 2700);
DISPLAY 0.872340 (3900 2700);
PAINT GREEN (3900 2700);
DISPLAY INVISIBLE (3900 2700);
FORCEPROP 2 LAST PATH I67
J 0
(3500 2850);
DISPLAY 0.680851 (3500 2850);
DISPLAY INVISIBLE (3500 2850);
FORCEADD OFFPAGE..1
(3775 2750);
FORCEPROP 2 LAST $XR0 298 
J 0
(3523 2750);
DISPLAY 0.638298 (3523 2750);
PAINT MONO (3523 2750);
FORCEPROP 2 LAST CDS_LIB standard
J 0
(3775 2750);
DISPLAY INVISIBLE (3775 2750);
FORCEPROP 1 LAST OFFPAGE TRUE
J 0
(4100 2625);
DISPLAY 0.872340 (4100 2625);
PAINT AQUA (4100 2625);
DISPLAY INVISIBLE (4100 2625);
FORCEPROP 1 LAST COMMENT_BODY TRUE
J 0
(3900 2650);
DISPLAY 0.872340 (3900 2650);
PAINT GREEN (3900 2650);
DISPLAY INVISIBLE (3900 2650);
FORCEPROP 2 LAST PATH I68
J 0
(3500 2800);
DISPLAY 0.680851 (3500 2800);
DISPLAY INVISIBLE (3500 2800);
FORCEADD OFFPAGE..1
(3775 2650);
FORCEPROP 2 LAST $XR0 309 
J 0
(3523 2650);
DISPLAY 0.638298 (3523 2650);
PAINT MONO (3523 2650);
FORCEPROP 2 LAST CDS_LIB standard
J 0
(3775 2650);
DISPLAY INVISIBLE (3775 2650);
FORCEPROP 1 LAST OFFPAGE TRUE
J 0
(4100 2525);
DISPLAY 0.872340 (4100 2525);
PAINT AQUA (4100 2525);
DISPLAY INVISIBLE (4100 2525);
FORCEPROP 1 LAST COMMENT_BODY TRUE
J 0
(3900 2550);
DISPLAY 0.872340 (3900 2550);
PAINT GREEN (3900 2550);
DISPLAY INVISIBLE (3900 2550);
FORCEPROP 2 LAST PATH I69
J 0
(3500 2700);
DISPLAY 0.680851 (3500 2700);
DISPLAY INVISIBLE (3500 2700);
FORCEADD OFFPAGE..2
R 2
(-1125 650);
FORCEPROP 2 LAST $XR0 297 
J 0
(-1410 650);
DISPLAY 0.638298 (-1410 650);
PAINT MONO (-1410 650);
FORCEPROP 2 LAST CDS_LIB standard
J 0
(-1125 650);
DISPLAY INVISIBLE (-1125 650);
FORCEPROP 1 LAST OFFPAGE TRUE
J 2
(-1450 525);
DISPLAY 0.872340 (-1450 525);
PAINT AQUA (-1450 525);
DISPLAY INVISIBLE (-1450 525);
FORCEPROP 1 LAST COMMENT_BODY TRUE
J 2
(-1080 555);
DISPLAY 0.872340 (-1080 555);
PAINT GREEN (-1080 555);
DISPLAY INVISIBLE (-1080 555);
FORCEPROP 2 LAST PATH I7
J 0
(-1400 700);
DISPLAY 0.680851 (-1400 700);
DISPLAY INVISIBLE (-1400 700);
FORCEADD OFFPAGE..2
R 2
(3775 2950);
FORCEPROP 2 LAST $XR0 308 
J 0
(3520 2950);
DISPLAY 0.638298 (3520 2950);
PAINT MONO (3520 2950);
FORCEPROP 2 LAST CDS_LIB standard
J 0
(3775 2950);
DISPLAY INVISIBLE (3775 2950);
FORCEPROP 1 LAST OFFPAGE TRUE
J 2
(3450 2825);
DISPLAY 0.872340 (3450 2825);
PAINT AQUA (3450 2825);
DISPLAY INVISIBLE (3450 2825);
FORCEPROP 1 LAST COMMENT_BODY TRUE
J 2
(3820 2855);
DISPLAY 0.872340 (3820 2855);
PAINT GREEN (3820 2855);
DISPLAY INVISIBLE (3820 2855);
FORCEPROP 2 LAST PATH I70
J 0
(3525 3000);
DISPLAY 0.680851 (3525 3000);
DISPLAY INVISIBLE (3525 3000);
FORCEADD OFFPAGE..5
(3775 2900);
FORCEPROP 2 LAST $XR0 308 
J 0
(3520 2900);
DISPLAY 0.638298 (3520 2900);
PAINT MONO (3520 2900);
FORCEPROP 2 LAST CDS_LIB standard
J 0
(3775 2900);
DISPLAY INVISIBLE (3775 2900);
FORCEPROP 1 LAST OFFPAGE TRUE
J 0
(4100 2775);
DISPLAY 0.872340 (4100 2775);
PAINT AQUA (4100 2775);
DISPLAY INVISIBLE (4100 2775);
FORCEPROP 1 LAST COMMENT_BODY TRUE
J 0
(3875 2825);
DISPLAY 1.170213 (3875 2825);
PAINT GREEN (3875 2825);
DISPLAY INVISIBLE (3875 2825);
FORCEPROP 2 LAST PATH I71
J 0
(3525 2950);
DISPLAY 0.680851 (3525 2950);
DISPLAY INVISIBLE (3525 2950);
FORCEADD OFFPAGE..5
(3775 3050);
FORCEPROP 2 LAST $XR0 297 
J 0
(3520 3050);
DISPLAY 0.638298 (3520 3050);
PAINT MONO (3520 3050);
FORCEPROP 2 LAST CDS_LIB standard
J 0
(3775 3050);
DISPLAY INVISIBLE (3775 3050);
FORCEPROP 1 LAST OFFPAGE TRUE
J 0
(4100 2925);
DISPLAY 0.872340 (4100 2925);
PAINT AQUA (4100 2925);
DISPLAY INVISIBLE (4100 2925);
FORCEPROP 1 LAST COMMENT_BODY TRUE
J 0
(3875 2975);
DISPLAY 1.170213 (3875 2975);
PAINT GREEN (3875 2975);
DISPLAY INVISIBLE (3875 2975);
FORCEPROP 2 LAST PATH I72
J 0
(3525 3100);
DISPLAY 0.680851 (3525 3100);
DISPLAY INVISIBLE (3525 3100);
FORCEADD OFFPAGE..2
R 2
(3775 3100);
FORCEPROP 2 LAST $XR0 297 
J 0
(3520 3100);
DISPLAY 0.638298 (3520 3100);
PAINT MONO (3520 3100);
FORCEPROP 2 LAST CDS_LIB standard
J 0
(3775 3100);
DISPLAY INVISIBLE (3775 3100);
FORCEPROP 1 LAST OFFPAGE TRUE
J 2
(3450 2975);
DISPLAY 0.872340 (3450 2975);
PAINT AQUA (3450 2975);
DISPLAY INVISIBLE (3450 2975);
FORCEPROP 1 LAST COMMENT_BODY TRUE
J 2
(3820 3005);
DISPLAY 0.872340 (3820 3005);
PAINT GREEN (3820 3005);
DISPLAY INVISIBLE (3820 3005);
FORCEPROP 2 LAST PATH I73
J 0
(3525 3150);
DISPLAY 0.680851 (3525 3150);
DISPLAY INVISIBLE (3525 3150);
FORCEADD UNIVERSAL_GND..1
(4850 -300);
FORCEPROP 3 LASTPIN (4850 -250) SIG_NAME GND\g
J 0
(4860 -240);
DISPLAY 0.659574 (4860 -240);
PAINT MONO (4860 -240);
DISPLAY INVISIBLE (4860 -240);
FORCEPROP 2 LAST CDS_LIB pure_quanta_power
J 0
(4850 -300);
DISPLAY INVISIBLE (4850 -300);
FORCEPROP 1 LAST HDL_POWER GND
J 1
(4875 -375);
DISPLAY 0.872340 (4875 -375);
PAINT GREEN (4875 -375);
DISPLAY INVISIBLE (4875 -375);
FORCEPROP 1 LAST PATH I74
J 0
(4925 -300);
DISPLAY 0.872340 (4925 -300);
PAINT AQUA (4925 -300);
DISPLAY INVISIBLE (4925 -300);
FORCEADD CONN112_10137002101LF..2
(6000 1650);
FORCEPROP 1 LAST LOCATION J105
J 0
(5250 3475);
DISPLAY 0.723404 (5250 3475);
PAINT GREEN (5250 3475);
FORCEPROP 0 LAST $SEC 2
J 0
(5250 3600);
DISPLAY 0.680851 (5250 3600);
PAINT MONO (5250 3600);
DISPLAY INVISIBLE (5250 3600);
FORCEPROP 0 LAST CDS_SEC 2
J 0
(5250 3600);
DISPLAY 1.021277 (5250 3600);
DISPLAY INVISIBLE (5250 3600);
FORCEPROP 0 LASTPIN (5075 750) $PN A1
J 2
(5065 760);
DISPLAY 0.680851 (5065 760);
PAINT MONO (5065 760);
FORCEPROP 0 LASTPIN (5075 1550) $PN A2
J 2
(5065 1560);
DISPLAY 0.680851 (5065 1560);
PAINT MONO (5065 1560);
FORCEPROP 0 LASTPIN (5075 2350) $PN A3
J 2
(5065 2360);
DISPLAY 0.680851 (5065 2360);
PAINT MONO (5065 2360);
FORCEPROP 0 LASTPIN (5075 3150) $PN A4
J 2
(5065 3160);
DISPLAY 0.680851 (5065 3160);
PAINT MONO (5065 3160);
FORCEPROP 0 LASTPIN (5075 700) $PN B1
J 2
(5065 710);
DISPLAY 0.680851 (5065 710);
PAINT MONO (5065 710);
FORCEPROP 0 LASTPIN (5075 1500) $PN B2
J 2
(5065 1510);
DISPLAY 0.680851 (5065 1510);
PAINT MONO (5065 1510);
FORCEPROP 0 LASTPIN (5075 2300) $PN B3
J 2
(5065 2310);
DISPLAY 0.680851 (5065 2310);
PAINT MONO (5065 2310);
FORCEPROP 0 LASTPIN (5075 3100) $PN B4
J 2
(5065 3110);
DISPLAY 0.680851 (5065 3110);
PAINT MONO (5065 3110);
FORCEPROP 0 LASTPIN (5075 650) $PN C1
J 2
(5065 660);
DISPLAY 0.680851 (5065 660);
PAINT MONO (5065 660);
FORCEPROP 0 LASTPIN (5075 1450) $PN C2
J 2
(5065 1460);
DISPLAY 0.680851 (5065 1460);
PAINT MONO (5065 1460);
FORCEPROP 0 LASTPIN (5075 2250) $PN C3
J 2
(5065 2260);
DISPLAY 0.680851 (5065 2260);
PAINT MONO (5065 2260);
FORCEPROP 0 LASTPIN (5075 3050) $PN C4
J 2
(5065 3060);
DISPLAY 0.680851 (5065 3060);
PAINT MONO (5065 3060);
FORCEPROP 0 LASTPIN (5075 600) $PN D1
J 2
(5065 610);
DISPLAY 0.680851 (5065 610);
PAINT MONO (5065 610);
FORCEPROP 0 LASTPIN (5075 1400) $PN D2
J 2
(5065 1410);
DISPLAY 0.680851 (5065 1410);
PAINT MONO (5065 1410);
FORCEPROP 0 LASTPIN (5075 2200) $PN D3
J 2
(5065 2210);
DISPLAY 0.680851 (5065 2210);
PAINT MONO (5065 2210);
FORCEPROP 0 LASTPIN (5075 3000) $PN D4
J 2
(5065 3010);
DISPLAY 0.680851 (5065 3010);
PAINT MONO (5065 3010);
FORCEPROP 0 LASTPIN (5075 550) $PN E1
J 2
(5065 560);
DISPLAY 0.680851 (5065 560);
PAINT MONO (5065 560);
FORCEPROP 0 LASTPIN (5075 1350) $PN E2
J 2
(5065 1360);
DISPLAY 0.680851 (5065 1360);
PAINT MONO (5065 1360);
FORCEPROP 0 LASTPIN (5075 2150) $PN E3
J 2
(5065 2160);
DISPLAY 0.680851 (5065 2160);
PAINT MONO (5065 2160);
FORCEPROP 0 LASTPIN (5075 2950) $PN E4
J 2
(5065 2960);
DISPLAY 0.680851 (5065 2960);
PAINT MONO (5065 2960);
FORCEPROP 0 LASTPIN (5075 500) $PN F1
J 2
(5065 510);
DISPLAY 0.680851 (5065 510);
PAINT MONO (5065 510);
FORCEPROP 0 LASTPIN (5075 1300) $PN F2
J 2
(5065 1310);
DISPLAY 0.680851 (5065 1310);
PAINT MONO (5065 1310);
FORCEPROP 0 LASTPIN (5075 2100) $PN F3
J 2
(5065 2110);
DISPLAY 0.680851 (5065 2110);
PAINT MONO (5065 2110);
FORCEPROP 0 LASTPIN (5075 2900) $PN F4
J 2
(5065 2910);
DISPLAY 0.680851 (5065 2910);
PAINT MONO (5065 2910);
FORCEPROP 0 LASTPIN (5075 450) $PN G1
J 2
(5065 460);
DISPLAY 0.680851 (5065 460);
PAINT MONO (5065 460);
FORCEPROP 0 LASTPIN (5075 1250) $PN G2
J 2
(5065 1260);
DISPLAY 0.680851 (5065 1260);
PAINT MONO (5065 1260);
FORCEPROP 0 LASTPIN (5075 2050) $PN G3
J 2
(5065 2060);
DISPLAY 0.680851 (5065 2060);
PAINT MONO (5065 2060);
FORCEPROP 0 LASTPIN (5075 2850) $PN G4
J 2
(5065 2860);
DISPLAY 0.680851 (5065 2860);
PAINT MONO (5065 2860);
FORCEPROP 0 LASTPIN (5075 400) $PN H1
J 2
(5065 410);
DISPLAY 0.680851 (5065 410);
PAINT MONO (5065 410);
FORCEPROP 0 LASTPIN (5075 1200) $PN H2
J 2
(5065 1210);
DISPLAY 0.680851 (5065 1210);
PAINT MONO (5065 1210);
FORCEPROP 0 LASTPIN (5075 2000) $PN H3
J 2
(5065 2010);
DISPLAY 0.680851 (5065 2010);
PAINT MONO (5065 2010);
FORCEPROP 0 LASTPIN (5075 2800) $PN H4
J 2
(5065 2810);
DISPLAY 0.680851 (5065 2810);
PAINT MONO (5065 2810);
FORCEPROP 0 LASTPIN (5075 350) $PN I1
J 2
(5065 360);
DISPLAY 0.680851 (5065 360);
PAINT MONO (5065 360);
FORCEPROP 0 LASTPIN (5075 1150) $PN I2
J 2
(5065 1160);
DISPLAY 0.680851 (5065 1160);
PAINT MONO (5065 1160);
FORCEPROP 0 LASTPIN (5075 1950) $PN I3
J 2
(5065 1960);
DISPLAY 0.680851 (5065 1960);
PAINT MONO (5065 1960);
FORCEPROP 0 LASTPIN (5075 2750) $PN I4
J 2
(5065 2760);
DISPLAY 0.680851 (5065 2760);
PAINT MONO (5065 2760);
FORCEPROP 0 LASTPIN (5075 300) $PN J1
J 2
(5065 310);
DISPLAY 0.680851 (5065 310);
PAINT MONO (5065 310);
FORCEPROP 0 LASTPIN (5075 1100) $PN J2
J 2
(5065 1110);
DISPLAY 0.680851 (5065 1110);
PAINT MONO (5065 1110);
FORCEPROP 0 LASTPIN (5075 1900) $PN J3
J 2
(5065 1910);
DISPLAY 0.680851 (5065 1910);
PAINT MONO (5065 1910);
FORCEPROP 0 LASTPIN (5075 2700) $PN J4
J 2
(5065 2710);
DISPLAY 0.680851 (5065 2710);
PAINT MONO (5065 2710);
FORCEPROP 0 LASTPIN (5075 250) $PN K1
J 2
(5065 260);
DISPLAY 0.680851 (5065 260);
PAINT MONO (5065 260);
FORCEPROP 0 LASTPIN (5075 1050) $PN K2
J 2
(5065 1060);
DISPLAY 0.680851 (5065 1060);
PAINT MONO (5065 1060);
FORCEPROP 0 LASTPIN (5075 1850) $PN K3
J 2
(5065 1860);
DISPLAY 0.680851 (5065 1860);
PAINT MONO (5065 1860);
FORCEPROP 0 LASTPIN (5075 2650) $PN K4
J 2
(5065 2660);
DISPLAY 0.680851 (5065 2660);
PAINT MONO (5065 2660);
FORCEPROP 0 LASTPIN (5075 200) $PN L1
J 2
(5065 210);
DISPLAY 0.680851 (5065 210);
PAINT MONO (5065 210);
FORCEPROP 0 LASTPIN (5075 1000) $PN L2
J 2
(5065 1010);
DISPLAY 0.680851 (5065 1010);
PAINT MONO (5065 1010);
FORCEPROP 0 LASTPIN (5075 1800) $PN L3
J 2
(5065 1810);
DISPLAY 0.680851 (5065 1810);
PAINT MONO (5065 1810);
FORCEPROP 0 LASTPIN (5075 2600) $PN L4
J 2
(5065 2610);
DISPLAY 0.680851 (5065 2610);
PAINT MONO (5065 2610);
FORCEPROP 0 LASTPIN (5075 150) $PN M1
J 2
(5065 160);
DISPLAY 0.680851 (5065 160);
PAINT MONO (5065 160);
FORCEPROP 0 LASTPIN (5075 950) $PN M2
J 2
(5065 960);
DISPLAY 0.680851 (5065 960);
PAINT MONO (5065 960);
FORCEPROP 0 LASTPIN (5075 1750) $PN M3
J 2
(5065 1760);
DISPLAY 0.680851 (5065 1760);
PAINT MONO (5065 1760);
FORCEPROP 0 LASTPIN (5075 2550) $PN M4
J 2
(5065 2560);
DISPLAY 0.680851 (5065 2560);
PAINT MONO (5065 2560);
FORCEPROP 0 LASTPIN (5075 100) $PN N1
J 2
(5065 110);
DISPLAY 0.680851 (5065 110);
PAINT MONO (5065 110);
FORCEPROP 0 LASTPIN (5075 900) $PN N2
J 2
(5065 910);
DISPLAY 0.680851 (5065 910);
PAINT MONO (5065 910);
FORCEPROP 0 LASTPIN (5075 1700) $PN N3
J 2
(5065 1710);
DISPLAY 0.680851 (5065 1710);
PAINT MONO (5065 1710);
FORCEPROP 0 LASTPIN (5075 2500) $PN N4
J 2
(5065 2510);
DISPLAY 0.680851 (5065 2510);
PAINT MONO (5065 2510);
FORCEPROP 2 LAST PART_TYPE THLF
J 0
(5250 3550);
DISPLAY 1.021277 (5250 3550);
FORCEPROP 1 LAST MATERIAL IO
J 0
(5258 3363);
DISPLAY 0.723404 (5258 3363);
PAINT GREEN (5258 3363);
FORCEPROP 1 LAST NEEDS_NO_SIZE TRUE
J 0
(6000 1650);
DISPLAY 0.723404 (6000 1650);
PAINT GREEN (6000 1650);
DISPLAY INVISIBLE (6000 1650);
FORCEPROP 0 LAST VALUE CONN112_10137002-101LF
J 0
(5250 3550);
DISPLAY 1.021277 (5250 3550);
DISPLAY INVISIBLE (5250 3550);
FORCEPROP 1 LAST CDS_LMAN_SYM_OUTLINE -775,1650,775,-1650
J 0
(6000 1650);
DISPLAY 0.468085 (6000 1650);
PAINT GREEN (6000 1650);
DISPLAY INVISIBLE (6000 1650);
FORCEPROP 2 LAST CDS_LIB pure_quanta
J 0
(6000 1650);
DISPLAY INVISIBLE (6000 1650);
FORCEPROP 1 LAST PATH I75
J 0
(6000 1650);
DISPLAY 0.723404 (6000 1650);
PAINT GREEN (6000 1650);
DISPLAY INVISIBLE (6000 1650);
FORCEPROP 1 LAST PART_NUMBER DFHSB2FR012
J 0
(5250 3425);
DISPLAY 0.723404 (5250 3425);
PAINT GREEN (5250 3425);
DISPLAY INVISIBLE (5250 3425);
FORCEADD CONN112_10137002101LF..1
(1075 1650);
FORCEPROP 1 LAST LOCATION J105
J 0
(325 3450);
DISPLAY 0.723404 (325 3450);
PAINT GREEN (325 3450);
FORCEPROP 0 LAST $SEC 1
J 0
(325 3575);
DISPLAY 0.680851 (325 3575);
PAINT MONO (325 3575);
DISPLAY INVISIBLE (325 3575);
FORCEPROP 0 LAST CDS_SEC 1
J 0
(325 3575);
DISPLAY 1.021277 (325 3575);
DISPLAY INVISIBLE (325 3575);
FORCEPROP 0 LASTPIN (150 750) $PN A5
J 2
(140 760);
DISPLAY 0.680851 (140 760);
PAINT MONO (140 760);
FORCEPROP 0 LASTPIN (150 1550) $PN A6
J 2
(140 1560);
DISPLAY 0.680851 (140 1560);
PAINT MONO (140 1560);
FORCEPROP 0 LASTPIN (150 2350) $PN A7
J 2
(140 2360);
DISPLAY 0.680851 (140 2360);
PAINT MONO (140 2360);
FORCEPROP 0 LASTPIN (150 3150) $PN A8
J 2
(140 3160);
DISPLAY 0.680851 (140 3160);
PAINT MONO (140 3160);
FORCEPROP 0 LASTPIN (150 700) $PN B5
J 2
(140 710);
DISPLAY 0.680851 (140 710);
PAINT MONO (140 710);
FORCEPROP 0 LASTPIN (150 1500) $PN B6
J 2
(140 1510);
DISPLAY 0.680851 (140 1510);
PAINT MONO (140 1510);
FORCEPROP 0 LASTPIN (150 2300) $PN B7
J 2
(140 2310);
DISPLAY 0.680851 (140 2310);
PAINT MONO (140 2310);
FORCEPROP 0 LASTPIN (150 3100) $PN B8
J 2
(140 3110);
DISPLAY 0.680851 (140 3110);
PAINT MONO (140 3110);
FORCEPROP 0 LASTPIN (150 650) $PN C5
J 2
(140 660);
DISPLAY 0.680851 (140 660);
PAINT MONO (140 660);
FORCEPROP 0 LASTPIN (150 1450) $PN C6
J 2
(140 1460);
DISPLAY 0.680851 (140 1460);
PAINT MONO (140 1460);
FORCEPROP 0 LASTPIN (150 2250) $PN C7
J 2
(140 2260);
DISPLAY 0.680851 (140 2260);
PAINT MONO (140 2260);
FORCEPROP 0 LASTPIN (150 3050) $PN C8
J 2
(140 3060);
DISPLAY 0.680851 (140 3060);
PAINT MONO (140 3060);
FORCEPROP 0 LASTPIN (150 600) $PN D5
J 2
(140 610);
DISPLAY 0.680851 (140 610);
PAINT MONO (140 610);
FORCEPROP 0 LASTPIN (150 1400) $PN D6
J 2
(140 1410);
DISPLAY 0.680851 (140 1410);
PAINT MONO (140 1410);
FORCEPROP 0 LASTPIN (150 2200) $PN D7
J 2
(140 2210);
DISPLAY 0.680851 (140 2210);
PAINT MONO (140 2210);
FORCEPROP 0 LASTPIN (150 3000) $PN D8
J 2
(140 3010);
DISPLAY 0.680851 (140 3010);
PAINT MONO (140 3010);
FORCEPROP 0 LASTPIN (150 550) $PN E5
J 2
(140 560);
DISPLAY 0.680851 (140 560);
PAINT MONO (140 560);
FORCEPROP 0 LASTPIN (150 1350) $PN E6
J 2
(140 1360);
DISPLAY 0.680851 (140 1360);
PAINT MONO (140 1360);
FORCEPROP 0 LASTPIN (150 2150) $PN E7
J 2
(140 2160);
DISPLAY 0.680851 (140 2160);
PAINT MONO (140 2160);
FORCEPROP 0 LASTPIN (150 2950) $PN E8
J 2
(140 2960);
DISPLAY 0.680851 (140 2960);
PAINT MONO (140 2960);
FORCEPROP 0 LASTPIN (150 500) $PN F5
J 2
(140 510);
DISPLAY 0.680851 (140 510);
PAINT MONO (140 510);
FORCEPROP 0 LASTPIN (150 1300) $PN F6
J 2
(140 1310);
DISPLAY 0.680851 (140 1310);
PAINT MONO (140 1310);
FORCEPROP 0 LASTPIN (150 2100) $PN F7
J 2
(140 2110);
DISPLAY 0.680851 (140 2110);
PAINT MONO (140 2110);
FORCEPROP 0 LASTPIN (150 2900) $PN F8
J 2
(140 2910);
DISPLAY 0.680851 (140 2910);
PAINT MONO (140 2910);
FORCEPROP 0 LASTPIN (150 450) $PN G5
J 2
(140 460);
DISPLAY 0.680851 (140 460);
PAINT MONO (140 460);
FORCEPROP 0 LASTPIN (150 1250) $PN G6
J 2
(140 1260);
DISPLAY 0.680851 (140 1260);
PAINT MONO (140 1260);
FORCEPROP 0 LASTPIN (150 2050) $PN G7
J 2
(140 2060);
DISPLAY 0.680851 (140 2060);
PAINT MONO (140 2060);
FORCEPROP 0 LASTPIN (150 2850) $PN G8
J 2
(140 2860);
DISPLAY 0.680851 (140 2860);
PAINT MONO (140 2860);
FORCEPROP 0 LASTPIN (150 400) $PN H5
J 2
(140 410);
DISPLAY 0.680851 (140 410);
PAINT MONO (140 410);
FORCEPROP 0 LASTPIN (150 1200) $PN H6
J 2
(140 1210);
DISPLAY 0.680851 (140 1210);
PAINT MONO (140 1210);
FORCEPROP 0 LASTPIN (150 2000) $PN H7
J 2
(140 2010);
DISPLAY 0.680851 (140 2010);
PAINT MONO (140 2010);
FORCEPROP 0 LASTPIN (150 2800) $PN H8
J 2
(140 2810);
DISPLAY 0.680851 (140 2810);
PAINT MONO (140 2810);
FORCEPROP 0 LASTPIN (150 350) $PN I5
J 2
(140 360);
DISPLAY 0.680851 (140 360);
PAINT MONO (140 360);
FORCEPROP 0 LASTPIN (150 1150) $PN I6
J 2
(140 1160);
DISPLAY 0.680851 (140 1160);
PAINT MONO (140 1160);
FORCEPROP 0 LASTPIN (150 1950) $PN I7
J 2
(140 1960);
DISPLAY 0.680851 (140 1960);
PAINT MONO (140 1960);
FORCEPROP 0 LASTPIN (150 2750) $PN I8
J 2
(140 2760);
DISPLAY 0.680851 (140 2760);
PAINT MONO (140 2760);
FORCEPROP 0 LASTPIN (150 300) $PN J5
J 2
(140 310);
DISPLAY 0.680851 (140 310);
PAINT MONO (140 310);
FORCEPROP 0 LASTPIN (150 1100) $PN J6
J 2
(140 1110);
DISPLAY 0.680851 (140 1110);
PAINT MONO (140 1110);
FORCEPROP 0 LASTPIN (150 1900) $PN J7
J 2
(140 1910);
DISPLAY 0.680851 (140 1910);
PAINT MONO (140 1910);
FORCEPROP 0 LASTPIN (150 2700) $PN J8
J 2
(140 2710);
DISPLAY 0.680851 (140 2710);
PAINT MONO (140 2710);
FORCEPROP 0 LASTPIN (150 250) $PN K5
J 2
(140 260);
DISPLAY 0.680851 (140 260);
PAINT MONO (140 260);
FORCEPROP 0 LASTPIN (150 1050) $PN K6
J 2
(140 1060);
DISPLAY 0.680851 (140 1060);
PAINT MONO (140 1060);
FORCEPROP 0 LASTPIN (150 1850) $PN K7
J 2
(140 1860);
DISPLAY 0.680851 (140 1860);
PAINT MONO (140 1860);
FORCEPROP 0 LASTPIN (150 2650) $PN K8
J 2
(140 2660);
DISPLAY 0.680851 (140 2660);
PAINT MONO (140 2660);
FORCEPROP 0 LASTPIN (150 200) $PN L5
J 2
(140 210);
DISPLAY 0.680851 (140 210);
PAINT MONO (140 210);
FORCEPROP 0 LASTPIN (150 1000) $PN L6
J 2
(140 1010);
DISPLAY 0.680851 (140 1010);
PAINT MONO (140 1010);
FORCEPROP 0 LASTPIN (150 1800) $PN L7
J 2
(140 1810);
DISPLAY 0.680851 (140 1810);
PAINT MONO (140 1810);
FORCEPROP 0 LASTPIN (150 2600) $PN L8
J 2
(140 2610);
DISPLAY 0.680851 (140 2610);
PAINT MONO (140 2610);
FORCEPROP 0 LASTPIN (150 150) $PN M5
J 2
(140 160);
DISPLAY 0.680851 (140 160);
PAINT MONO (140 160);
FORCEPROP 0 LASTPIN (150 950) $PN M6
J 2
(140 960);
DISPLAY 0.680851 (140 960);
PAINT MONO (140 960);
FORCEPROP 0 LASTPIN (150 1750) $PN M7
J 2
(140 1760);
DISPLAY 0.680851 (140 1760);
PAINT MONO (140 1760);
FORCEPROP 0 LASTPIN (150 2550) $PN M8
J 2
(140 2560);
DISPLAY 0.680851 (140 2560);
PAINT MONO (140 2560);
FORCEPROP 0 LASTPIN (150 100) $PN N5
J 2
(140 110);
DISPLAY 0.680851 (140 110);
PAINT MONO (140 110);
FORCEPROP 0 LASTPIN (150 900) $PN N6
J 2
(140 910);
DISPLAY 0.680851 (140 910);
PAINT MONO (140 910);
FORCEPROP 0 LASTPIN (150 1700) $PN N7
J 2
(140 1710);
DISPLAY 0.680851 (140 1710);
PAINT MONO (140 1710);
FORCEPROP 0 LASTPIN (150 2500) $PN N8
J 2
(140 2510);
DISPLAY 0.680851 (140 2510);
PAINT MONO (140 2510);
FORCEPROP 1 LAST MATERIAL IO
J 0
(330 3332);
DISPLAY 0.723404 (330 3332);
PAINT GREEN (330 3332);
FORCEPROP 2 LAST PART_TYPE THLF
J 0
(325 3525);
DISPLAY 1.021277 (325 3525);
FORCEPROP 0 LAST VALUE CONN112_10137002-101LF
J 0
(350 3650);
DISPLAY 1.021277 (350 3650);
DISPLAY INVISIBLE (350 3650);
FORCEPROP 1 LAST NEEDS_NO_SIZE TRUE
J 0
(1075 1650);
DISPLAY 0.723404 (1075 1650);
PAINT GREEN (1075 1650);
DISPLAY INVISIBLE (1075 1650);
FORCEPROP 1 LAST CDS_LMAN_SYM_OUTLINE -775,1650,775,-1650
J 0
(1075 1650);
DISPLAY 0.468085 (1075 1650);
PAINT GREEN (1075 1650);
DISPLAY INVISIBLE (1075 1650);
FORCEPROP 2 LAST CDS_LIB pure_quanta
J 0
(1075 1650);
DISPLAY INVISIBLE (1075 1650);
FORCEPROP 1 LAST PATH I76
J 0
(1075 1650);
DISPLAY 0.723404 (1075 1650);
PAINT GREEN (1075 1650);
DISPLAY INVISIBLE (1075 1650);
FORCEPROP 1 LAST PART_NUMBER DFHSB2FR012
J 0
(325 3400);
DISPLAY 0.723404 (325 3400);
PAINT GREEN (325 3400);
DISPLAY INVISIBLE (325 3400);
FORCEADD OFFPAGE..2
R 2
(-1125 750);
FORCEPROP 2 LAST $XR0 124 
J 0
(-1410 750);
DISPLAY 0.638298 (-1410 750);
PAINT MONO (-1410 750);
FORCEPROP 2 LAST CDS_LIB standard
J 0
(-1125 750);
DISPLAY INVISIBLE (-1125 750);
FORCEPROP 1 LAST OFFPAGE TRUE
J 2
(-1450 625);
DISPLAY 0.872340 (-1450 625);
PAINT AQUA (-1450 625);
DISPLAY INVISIBLE (-1450 625);
FORCEPROP 1 LAST COMMENT_BODY TRUE
J 2
(-1080 655);
DISPLAY 0.872340 (-1080 655);
PAINT GREEN (-1080 655);
DISPLAY INVISIBLE (-1080 655);
FORCEPROP 2 LAST PATH I8
J 0
(-1400 800);
DISPLAY 0.680851 (-1400 800);
DISPLAY INVISIBLE (-1400 800);
FORCEADD OFFPAGE..5
(-1125 600);
FORCEPROP 2 LAST $XR0 297 
J 0
(-1410 600);
DISPLAY 0.638298 (-1410 600);
PAINT MONO (-1410 600);
FORCEPROP 2 LAST CDS_LIB standard
J 0
(-1125 600);
DISPLAY INVISIBLE (-1125 600);
FORCEPROP 1 LAST OFFPAGE TRUE
J 0
(-800 475);
DISPLAY 0.872340 (-800 475);
PAINT AQUA (-800 475);
DISPLAY INVISIBLE (-800 475);
FORCEPROP 1 LAST COMMENT_BODY TRUE
J 0
(-1025 525);
DISPLAY 1.170213 (-1025 525);
PAINT GREEN (-1025 525);
DISPLAY INVISIBLE (-1025 525);
FORCEPROP 2 LAST PATH I9
J 0
(-1400 650);
DISPLAY 0.680851 (-1400 650);
DISPLAY INVISIBLE (-1400 650);
FORCEADD QUANTA_TITLE_BLOCK_C..1
(6950 -1625);
FORCEPROP 0 LAST CDS_CON_LAST_MODIFIED Thu Sep 14 16:12:58 2023
J 0
(5065 -1610);
PAINT MONO (5065 -1610);
DISPLAY INVISIBLE (5065 -1610);
FORCEPROP 2 LAST CUSTOM_TXT_CDS <XR_PAGE_TITLE>
J 0
(-940 3625);
DISPLAY 0.638298 (-940 3625);
PAINT PINK (-940 3625);
DISPLAY INVISIBLE (-940 3625);
FORCEPROP 2 LAST CUSTOM_TXT_CDS <CON_LAST_MODIFIED>
J 0
(5100 -1625);
DISPLAY 0.978723 (5100 -1625);
FORCEPROP 2 LAST CUSTOM_TXT_CDS <Q_PROJ>
J 0
(4568 -1523);
DISPLAY 1.212766 (4568 -1523);
FORCEPROP 2 LAST CUSTOM_TXT_CDS <NAME_2>
J 0
(3775 -1575);
FORCEPROP 2 LAST CUSTOM_TXT_CDS <Q_REV>
J 0
(6766 -1522);
DISPLAY 1.212766 (6766 -1522);
FORCEPROP 2 LAST CUSTOM_TXT_CDS <NAME_1>
J 0
(3775 -1450);
FORCEPROP 2 LAST CUSTOM_TXT_CDS <Q_NUMBER>
J 0
(5547 -1522);
DISPLAY 1.212766 (5547 -1522);
FORCEPROP 2 LAST CUSTOM_TXT_CDS <CON_PAGE_NUM> OF <CON_TOTAL_PAGES>
J 0
(6504 -1607);
DISPLAY 0.978723 (6504 -1607);
FORCEPROP 1 LAST Q_TITLE PCIE - CPU0_EXAMAX_P2/P3_X16
J 0
(-2325 -1575);
DISPLAY 1.957447 (-2325 -1575);
PAINT GREEN (-2325 -1575);
FORCEPROP 1 LAST CDS_LMAN_SYM_OUTLINE -9475,6775,100,-125
J 0
(6950 -1625);
DISPLAY 0.468085 (6950 -1625);
PAINT GREEN (6950 -1625);
DISPLAY INVISIBLE (6950 -1625);
FORCEPROP 2 LAST CDS_LIB pure_quanta
J 0
(6950 -1625);
PAINT MONO (6950 -1625);
DISPLAY INVISIBLE (6950 -1625);
FORCEPROP 2 LAST PAGE_BORDER TRUE
J 0
(-940 3625);
DISPLAY 0.638298 (-940 3625);
PAINT PINK (-940 3625);
DISPLAY INVISIBLE (-940 3625);
FORCEPROP 2 LAST CDS_XR_PAGE_TITLE CR-115 : @T6G_MB_LIB.T6G(SCH_1):PAGE115
J 0
(-940 3625);
DISPLAY 0.638298 (-940 3625);
PAINT PINK (-940 3625);
DISPLAY INVISIBLE (-940 3625);
FORCEPROP 1 LAST Q_DEPT BU9
J 1
(3187 -1576);
DISPLAY 1.957447 (3187 -1576);
PAINT GREEN (3187 -1576);
DISPLAY INVISIBLE (3187 -1576);
FORCEPROP 1 LAST COMMENT_BODY TRUE
J 0
(6962 -1638);
DISPLAY 0.978723 (6962 -1638);
PAINT GREEN (6962 -1638);
DISPLAY INVISIBLE (6962 -1638);
WIRE 16 -1 (5075 2500)(3825 2500);
FORCEPROP 2 LAST SIG_NAME FM_SWB_BIC_READY_N
J 0
(3990 2510);
DISPLAY 0.638298 (3990 2510);
WIRE 16 -1 (5075 2350)(3825 2350);
FORCEPROP 2 LAST SIG_NAME GPU_WP_HW_CTRL_ISO_N
J 0
(3990 2360);
DISPLAY 0.638298 (3990 2360);
WIRE 16 -1 (5075 2250)(3825 2250);
FORCEPROP 2 LAST SIG_NAME P5E_CPU0_P2_RX_BUF_DN<10>
J 0
(3990 2260);
DISPLAY 0.638298 (3990 2260);
WIRE 16 -1 (5075 3150)(4850 3150);
WIRE 16 -1 (4850 3150)(4850 3000);
WIRE 16 -1 (5075 3000)(4850 3000);
WIRE 16 -1 (4850 3000)(4850 2850);
WIRE 16 -1 (5075 2850)(4850 2850);
WIRE 16 -1 (4850 2850)(4850 2700);
WIRE 16 -1 (5075 2700)(4850 2700);
WIRE 16 -1 (4850 2700)(4850 2550);
WIRE 16 -1 (5075 2550)(4850 2550);
WIRE 16 -1 (4850 2550)(4850 2300);
WIRE 16 -1 (5075 2300)(4850 2300);
WIRE 16 -1 (4850 2300)(4850 2150);
WIRE 16 -1 (5075 2150)(4850 2150);
WIRE 16 -1 (4850 2150)(4850 2000);
WIRE 16 -1 (5075 2000)(4850 2000);
WIRE 16 -1 (4850 2000)(4850 1850);
WIRE 16 -1 (5075 1850)(4850 1850);
WIRE 16 -1 (4850 1850)(4850 1700);
WIRE 16 -1 (5075 1700)(4850 1700);
WIRE 16 -1 (4850 1700)(4850 1550);
WIRE 16 -1 (5075 1550)(4850 1550);
WIRE 16 -1 (4850 1550)(4850 1400);
WIRE 16 -1 (5075 1400)(4850 1400);
WIRE 16 -1 (4850 1400)(4850 1250);
WIRE 16 -1 (5075 1250)(4850 1250);
WIRE 16 -1 (4850 1250)(4850 1100);
WIRE 16 -1 (5075 1100)(4850 1100);
WIRE 16 -1 (4850 1100)(4850 950);
WIRE 16 -1 (5075 950)(4850 950);
WIRE 16 -1 (4850 950)(4850 700);
WIRE 16 -1 (5075 700)(4850 700);
WIRE 16 -1 (4850 700)(4850 550);
WIRE 16 -1 (5075 550)(4850 550);
WIRE 16 -1 (4850 550)(4850 400);
WIRE 16 -1 (5075 400)(4850 400);
WIRE 16 -1 (4850 400)(4850 250);
WIRE 16 -1 (5075 250)(4850 250);
WIRE 16 -1 (4850 250)(4850 100);
WIRE 16 -1 (5075 100)(4850 100);
WIRE 16 -1 (4850 100)(4850 -250);
WIRE 16 -1 (5075 2600)(3825 2600);
FORCEPROP 2 LAST SIG_NAME P5E_CPU0_P3_TX_BUF_C_DP<11>
J 0
(3990 2610);
DISPLAY 0.638298 (3990 2610);
WIRE 16 -1 (5075 2650)(3825 2650);
FORCEPROP 2 LAST SIG_NAME P5E_CPU0_P3_TX_BUF_C_DN<11>
J 0
(3990 2660);
DISPLAY 0.638298 (3990 2660);
WIRE 16 -1 (5075 2750)(3825 2750);
FORCEPROP 2 LAST SIG_NAME P5E_CPU0_P2_TX_BUF_C_DP<11>
J 0
(3990 2760);
DISPLAY 0.638298 (3990 2760);
WIRE 16 -1 (5075 2200)(3825 2200);
FORCEPROP 2 LAST SIG_NAME P5E_CPU0_P2_RX_BUF_DP<10>
J 0
(3990 2210);
DISPLAY 0.638298 (3990 2210);
WIRE 16 -1 (5075 2050)(3825 2050);
FORCEPROP 2 LAST SIG_NAME P5E_CPU0_P3_RX_BUF_DP<10>
J 0
(3990 2060);
DISPLAY 0.638298 (3990 2060);
WIRE 16 -1 (5075 150)(3850 150);
FORCEPROP 2 LAST SIG_NAME P5E_CPU0_P3_TX_BUF_C_DP<8>
J 0
(3990 160);
DISPLAY 0.638298 (3990 160);
WIRE 16 -1 (5075 200)(3850 200);
FORCEPROP 2 LAST SIG_NAME P5E_CPU0_P3_TX_BUF_C_DN<8>
J 0
(3990 210);
DISPLAY 0.638298 (3990 210);
WIRE 16 -1 (5075 300)(3850 300);
FORCEPROP 2 LAST SIG_NAME P5E_CPU0_P2_TX_BUF_C_DP<8>
J 0
(3990 310);
DISPLAY 0.638298 (3990 310);
WIRE 16 -1 (5075 350)(3850 350);
FORCEPROP 2 LAST SIG_NAME P5E_CPU0_P2_TX_BUF_C_DN<8>
J 0
(3990 360);
DISPLAY 0.638298 (3990 360);
WIRE 16 -1 (5075 450)(3850 450);
FORCEPROP 2 LAST SIG_NAME P5E_CPU0_P3_RX_BUF_DP<8>
J 0
(3990 460);
DISPLAY 0.638298 (3990 460);
WIRE 16 -1 (5075 500)(3850 500);
FORCEPROP 2 LAST SIG_NAME P5E_CPU0_P3_RX_BUF_DN<8>
J 0
(3990 510);
DISPLAY 0.638298 (3990 510);
WIRE 16 -1 (5075 600)(3850 600);
FORCEPROP 2 LAST SIG_NAME P5E_CPU0_P2_RX_BUF_DP<8>
J 0
(3990 610);
DISPLAY 0.638298 (3990 610);
WIRE 16 -1 (5075 650)(3850 650);
FORCEPROP 2 LAST SIG_NAME P5E_CPU0_P2_RX_BUF_DN<8>
J 0
(3990 660);
DISPLAY 0.638298 (3990 660);
WIRE 16 -1 (5075 750)(3850 750);
FORCEPROP 2 LAST SIG_NAME GPU_3V3IO_RSVD4
J 0
(3990 760);
DISPLAY 0.638298 (3990 760);
WIRE 16 -1 (5075 1350)(3850 1350);
FORCEPROP 2 LAST SIG_NAME P5E_CPU0_P3_RX_BUF_DN<9>
J 0
(3990 1360);
DISPLAY 0.638298 (3990 1360);
WIRE 16 -1 (5075 1300)(3850 1300);
FORCEPROP 2 LAST SIG_NAME P5E_CPU0_P3_RX_BUF_DP<9>
J 0
(3990 1310);
DISPLAY 0.638298 (3990 1310);
WIRE 16 -1 (5075 1200)(3850 1200);
FORCEPROP 2 LAST SIG_NAME P5E_CPU0_P2_TX_BUF_C_DN<9>
J 0
(3990 1210);
DISPLAY 0.638298 (3990 1210);
WIRE 16 -1 (5075 1150)(3850 1150);
FORCEPROP 2 LAST SIG_NAME P5E_CPU0_P2_TX_BUF_C_DP<9>
J 0
(3990 1160);
DISPLAY 0.638298 (3990 1160);
WIRE 16 -1 (5075 1000)(3850 1000);
FORCEPROP 2 LAST SIG_NAME P5E_CPU0_P3_TX_BUF_C_DP<9>
J 0
(3990 1010);
DISPLAY 0.638298 (3990 1010);
WIRE 16 -1 (5075 900)(3850 900);
FORCEPROP 2 LAST SIG_NAME FM_SWB_PWR_EN_R_BUF
J 0
(3990 910);
DISPLAY 0.638298 (3990 910);
WIRE 16 -1 (5075 1050)(3850 1050);
FORCEPROP 2 LAST SIG_NAME P5E_CPU0_P3_TX_BUF_C_DN<9>
J 0
(3990 1060);
DISPLAY 0.638298 (3990 1060);
WIRE 16 -1 (5075 1800)(3825 1800);
FORCEPROP 2 LAST SIG_NAME P5E_CPU0_P3_TX_BUF_C_DN<10>
J 0
(3990 1810);
DISPLAY 0.638298 (3990 1810);
WIRE 16 -1 (5075 1900)(3825 1900);
FORCEPROP 2 LAST SIG_NAME P5E_CPU0_P2_TX_BUF_C_DP<10>
J 0
(3990 1910);
DISPLAY 0.638298 (3990 1910);
WIRE 16 -1 (5075 1750)(3825 1750);
FORCEPROP 2 LAST SIG_NAME P5E_CPU0_P3_TX_BUF_C_DP<10>
J 0
(3990 1760);
DISPLAY 0.638298 (3990 1760);
WIRE 16 -1 (5075 1950)(3825 1950);
FORCEPROP 2 LAST SIG_NAME P5E_CPU0_P2_TX_BUF_C_DN<10>
J 0
(3990 1960);
DISPLAY 0.638298 (3990 1960);
WIRE 16 -1 (5075 2100)(3825 2100);
FORCEPROP 2 LAST SIG_NAME P5E_CPU0_P3_RX_BUF_DN<10>
J 0
(3990 2110);
DISPLAY 0.638298 (3990 2110);
WIRE 16 -1 (150 600)(-1075 600);
FORCEPROP 2 LAST SIG_NAME P5E_CPU0_P2_RX_BUF_DP<12>
J 0
(-910 610);
DISPLAY 0.638298 (-910 610);
WIRE 16 -1 (150 650)(-1075 650);
FORCEPROP 2 LAST SIG_NAME P5E_CPU0_P2_RX_BUF_DN<12>
J 0
(-910 660);
DISPLAY 0.638298 (-910 660);
WIRE 16 -1 (150 900)(-1075 900);
FORCEPROP 2 LAST SIG_NAME RST_SWB_BIC_BUF_N
J 0
(-910 910);
DISPLAY 0.638298 (-910 910);
WIRE 16 -1 (150 1000)(-1075 1000);
FORCEPROP 2 LAST SIG_NAME P5E_CPU0_P3_TX_BUF_C_DP<13>
J 0
(-910 1010);
DISPLAY 0.638298 (-910 1010);
WIRE 16 -1 (150 1300)(-1075 1300);
FORCEPROP 2 LAST SIG_NAME P5E_CPU0_P3_RX_BUF_DP<13>
J 0
(-910 1310);
DISPLAY 0.638298 (-910 1310);
WIRE 16 -1 (150 1900)(-1075 1900);
FORCEPROP 2 LAST SIG_NAME P5E_CPU0_P2_TX_BUF_C_DP<14>
J 0
(-910 1910);
DISPLAY 0.638298 (-910 1910);
WIRE 16 -1 (150 1950)(-1075 1950);
FORCEPROP 2 LAST SIG_NAME P5E_CPU0_P2_TX_BUF_C_DN<14>
J 0
(-910 1960);
DISPLAY 0.638298 (-910 1960);
WIRE 16 -1 (150 2050)(-1075 2050);
FORCEPROP 2 LAST SIG_NAME P5E_CPU0_P3_RX_BUF_DP<14>
J 0
(-910 2060);
DISPLAY 0.638298 (-910 2060);
WIRE 16 -1 (150 2100)(-1075 2100);
FORCEPROP 2 LAST SIG_NAME P5E_CPU0_P3_RX_BUF_DN<14>
J 0
(-910 2110);
DISPLAY 0.638298 (-910 2110);
WIRE 16 -1 (150 250)(-25 250);
WIRE 16 -1 (-25 400)(-25 250);
WIRE 16 -1 (-25 250)(-25 100);
WIRE 16 -1 (150 100)(-25 100);
WIRE 16 -1 (-25 100)(-25 -200);
WIRE 16 -1 (150 400)(-25 400);
WIRE 16 -1 (-25 400)(-25 550);
WIRE 16 -1 (150 550)(-25 550);
WIRE 16 -1 (-25 550)(-25 700);
WIRE 16 -1 (150 700)(-25 700);
WIRE 16 -1 (-25 950)(-25 700);
WIRE 16 -1 (150 950)(-25 950);
WIRE 16 -1 (-25 1100)(-25 950);
WIRE 16 -1 (150 1100)(-25 1100);
WIRE 16 -1 (-25 1250)(-25 1100);
WIRE 16 -1 (150 1250)(-25 1250);
WIRE 16 -1 (-25 1400)(-25 1250);
WIRE 16 -1 (150 1400)(-25 1400);
WIRE 16 -1 (-25 1550)(-25 1400);
WIRE 16 -1 (150 1550)(-25 1550);
WIRE 16 -1 (-25 1700)(-25 1550);
WIRE 16 -1 (150 1700)(-25 1700);
WIRE 16 -1 (-25 1850)(-25 1700);
WIRE 16 -1 (150 1850)(-25 1850);
WIRE 16 -1 (-25 2000)(-25 1850);
WIRE 16 -1 (150 2000)(-25 2000);
WIRE 16 -1 (-25 2150)(-25 2000);
WIRE 16 -1 (150 2150)(-25 2150);
WIRE 16 -1 (-25 2300)(-25 2150);
WIRE 16 -1 (150 2300)(-25 2300);
WIRE 16 -1 (-25 2550)(-25 2300);
WIRE 16 -1 (150 2550)(-25 2550);
WIRE 16 -1 (-25 2700)(-25 2550);
WIRE 16 -1 (150 2700)(-25 2700);
WIRE 16 -1 (-25 2850)(-25 2700);
WIRE 16 -1 (150 2850)(-25 2850);
WIRE 16 -1 (-25 3000)(-25 2850);
WIRE 16 -1 (150 3000)(-25 3000);
WIRE 16 -1 (-25 3150)(-25 3000);
WIRE 16 -1 (150 3150)(-25 3150);
WIRE 16 -1 (5075 2900)(3825 2900);
FORCEPROP 2 LAST SIG_NAME P5E_CPU0_P3_RX_BUF_DP<11>
J 0
(3990 2910);
DISPLAY 0.638298 (3990 2910);
WIRE 16 -1 (5075 2800)(3825 2800);
FORCEPROP 2 LAST SIG_NAME P5E_CPU0_P2_TX_BUF_C_DN<11>
J 0
(3990 2810);
DISPLAY 0.638298 (3990 2810);
WIRE 16 -1 (5075 2950)(3825 2950);
FORCEPROP 2 LAST SIG_NAME P5E_CPU0_P3_RX_BUF_DN<11>
J 0
(3990 2960);
DISPLAY 0.638298 (3990 2960);
WIRE 16 -1 (150 500)(-1075 500);
FORCEPROP 2 LAST SIG_NAME P5E_CPU0_P3_RX_BUF_DN<12>
J 0
(-910 510);
DISPLAY 0.638298 (-910 510);
WIRE 16 -1 (150 750)(-1075 750);
FORCEPROP 2 LAST SIG_NAME GPU_3V3IO_RSVD3
J 0
(-910 760);
DISPLAY 0.638298 (-910 760);
WIRE 16 -1 (150 1150)(-1075 1150);
FORCEPROP 2 LAST SIG_NAME P5E_CPU0_P2_TX_BUF_C_DP<13>
J 0
(-910 1160);
DISPLAY 0.638298 (-910 1160);
WIRE 16 -1 (150 1350)(-1075 1350);
FORCEPROP 2 LAST SIG_NAME P5E_CPU0_P3_RX_BUF_DN<13>
J 0
(-910 1360);
DISPLAY 0.638298 (-910 1360);
WIRE 16 -1 (150 1450)(-1075 1450);
FORCEPROP 2 LAST SIG_NAME P5E_CPU0_P2_RX_BUF_DP<13>
J 0
(-910 1460);
DISPLAY 0.638298 (-910 1460);
WIRE 16 -1 (150 1500)(-1075 1500);
FORCEPROP 2 LAST SIG_NAME P5E_CPU0_P2_RX_BUF_DN<13>
J 0
(-910 1510);
DISPLAY 0.638298 (-910 1510);
WIRE 16 -1 (150 1750)(-1075 1750);
FORCEPROP 2 LAST SIG_NAME P5E_CPU0_P3_TX_BUF_C_DP<14>
J 0
(-910 1760);
DISPLAY 0.638298 (-910 1760);
WIRE 16 -1 (150 1800)(-1075 1800);
FORCEPROP 2 LAST SIG_NAME P5E_CPU0_P3_TX_BUF_C_DN<14>
J 0
(-910 1810);
DISPLAY 0.638298 (-910 1810);
WIRE 16 -1 (150 2200)(-1075 2200);
FORCEPROP 2 LAST SIG_NAME P5E_CPU0_P2_RX_BUF_DP<14>
J 0
(-910 2210);
DISPLAY 0.638298 (-910 2210);
WIRE 16 -1 (150 2250)(-1075 2250);
FORCEPROP 2 LAST SIG_NAME P5E_CPU0_P2_RX_BUF_DN<14>
J 0
(-910 2260);
DISPLAY 0.638298 (-910 2260);
WIRE 16 -1 (150 2350)(-1075 2350);
FORCEPROP 2 LAST SIG_NAME GPU_3V3IO_RSVD1
J 0
(-910 2360);
DISPLAY 0.638298 (-910 2360);
WIRE 16 -1 (150 2500)(-1075 2500);
FORCEPROP 2 LAST SIG_NAME RST_BMC_FROM_SWB_N
J 0
(-910 2510);
DISPLAY 0.638298 (-910 2510);
WIRE 16 -1 (150 2650)(-1075 2650);
FORCEPROP 2 LAST SIG_NAME P5E_CPU0_P3_TX_BUF_C_DN<15>
J 0
(-910 2660);
DISPLAY 0.638298 (-910 2660);
WIRE 16 -1 (150 2750)(-1075 2750);
FORCEPROP 2 LAST SIG_NAME P5E_CPU0_P2_TX_BUF_C_DP<15>
J 0
(-910 2760);
DISPLAY 0.638298 (-910 2760);
WIRE 16 -1 (150 2600)(-1075 2600);
FORCEPROP 2 LAST SIG_NAME P5E_CPU0_P3_TX_BUF_C_DP<15>
J 0
(-910 2610);
DISPLAY 0.638298 (-910 2610);
WIRE 16 -1 (150 2900)(-1075 2900);
FORCEPROP 2 LAST SIG_NAME P5E_CPU0_P3_RX_BUF_DP<15>
J 0
(-910 2910);
DISPLAY 0.638298 (-910 2910);
WIRE 16 -1 (150 2950)(-1075 2950);
FORCEPROP 2 LAST SIG_NAME P5E_CPU0_P3_RX_BUF_DN<15>
J 0
(-910 2960);
DISPLAY 0.638298 (-910 2960);
WIRE 16 -1 (150 2800)(-1075 2800);
FORCEPROP 2 LAST SIG_NAME P5E_CPU0_P2_TX_BUF_C_DN<15>
J 0
(-910 2810);
DISPLAY 0.638298 (-910 2810);
WIRE 16 -1 (150 1050)(-1075 1050);
FORCEPROP 2 LAST SIG_NAME P5E_CPU0_P3_TX_BUF_C_DN<13>
J 0
(-910 1060);
DISPLAY 0.638298 (-910 1060);
WIRE 16 -1 (150 150)(-1075 150);
FORCEPROP 2 LAST SIG_NAME P5E_CPU0_P3_TX_BUF_C_DP<12>
J 0
(-910 160);
DISPLAY 0.638298 (-910 160);
WIRE 16 -1 (150 200)(-1075 200);
FORCEPROP 2 LAST SIG_NAME P5E_CPU0_P3_TX_BUF_C_DN<12>
J 0
(-910 210);
DISPLAY 0.638298 (-910 210);
WIRE 16 -1 (150 300)(-1075 300);
FORCEPROP 2 LAST SIG_NAME P5E_CPU0_P2_TX_BUF_C_DP<12>
J 0
(-910 310);
DISPLAY 0.638298 (-910 310);
WIRE 16 -1 (150 450)(-1075 450);
FORCEPROP 2 LAST SIG_NAME P5E_CPU0_P3_RX_BUF_DP<12>
J 0
(-910 460);
DISPLAY 0.638298 (-910 460);
WIRE 16 -1 (150 1200)(-1075 1200);
FORCEPROP 2 LAST SIG_NAME P5E_CPU0_P2_TX_BUF_C_DN<13>
J 0
(-910 1210);
DISPLAY 0.638298 (-910 1210);
WIRE 16 -1 (150 3050)(-1075 3050);
FORCEPROP 2 LAST SIG_NAME P5E_CPU0_P2_RX_BUF_DP<15>
J 0
(-910 3060);
DISPLAY 0.638298 (-910 3060);
WIRE 16 -1 (150 3100)(-1075 3100);
FORCEPROP 2 LAST SIG_NAME P5E_CPU0_P2_RX_BUF_DN<15>
J 0
(-910 3110);
DISPLAY 0.638298 (-910 3110);
WIRE 16 -1 (5075 1450)(3850 1450);
FORCEPROP 2 LAST SIG_NAME P5E_CPU0_P2_RX_BUF_DP<9>
J 0
(3990 1460);
DISPLAY 0.638298 (3990 1460);
WIRE 16 -1 (5075 1500)(3850 1500);
FORCEPROP 2 LAST SIG_NAME P5E_CPU0_P2_RX_BUF_DN<9>
J 0
(3990 1510);
DISPLAY 0.638298 (3990 1510);
WIRE 16 -1 (5075 3100)(3825 3100);
FORCEPROP 2 LAST SIG_NAME P5E_CPU0_P2_RX_BUF_DN<11>
J 0
(3990 3110);
DISPLAY 0.638298 (3990 3110);
WIRE 16 -1 (5075 3050)(3825 3050);
FORCEPROP 2 LAST SIG_NAME P5E_CPU0_P2_RX_BUF_DP<11>
J 0
(3990 3060);
DISPLAY 0.638298 (3990 3060);
WIRE 16 -1 (150 350)(-1075 350);
FORCEPROP 2 LAST SIG_NAME P5E_CPU0_P2_TX_BUF_C_DN<12>
J 0
(-910 360);
DISPLAY 0.638298 (-910 360);
DOT 1 (-25 950);
DOT 1 (-25 250);
DOT 1 (-25 100);
DOT 1 (-25 400);
DOT 1 (-25 550);
DOT 1 (-25 1100);
DOT 1 (-25 1250);
DOT 1 (-25 1400);
DOT 1 (-25 1550);
DOT 1 (-25 1700);
DOT 1 (-25 2000);
DOT 1 (-25 1850);
DOT 1 (-25 2300);
DOT 1 (-25 2150);
DOT 1 (-25 2550);
DOT 1 (-25 2700);
DOT 1 (-25 2850);
DOT 1 (-25 3000);
DOT 1 (4850 100);
DOT 1 (4850 250);
DOT 1 (4850 400);
DOT 1 (4850 700);
DOT 1 (4850 550);
DOT 1 (4850 950);
DOT 1 (4850 1250);
DOT 1 (4850 1100);
DOT 1 (4850 1400);
DOT 1 (4850 1550);
DOT 1 (4850 1700);
DOT 1 (4850 1850);
DOT 1 (4850 2150);
DOT 1 (4850 2550);
DOT 1 (4850 2700);
DOT 1 (4850 3000);
DOT 1 (4850 2850);
DOT 1 (-25 700);
DOT 1 (4850 2300);
DOT 1 (4850 2000);
FORCENOTE
CPU0_P2_TX/RX<0-15> LANE REVERSAL
(-2150 3825) 0;
DISPLAY LEFT (-2150 3825);
DISPLAY 1.595745 (-2150 3825);
PAINT PINK (-2150 3825);
FORCENOTE
CPU0_P3_TX/RX<0-15> LANE REVERSAL
(-2150 3725) 0;
DISPLAY LEFT (-2150 3725);
DISPLAY 1.595745 (-2150 3725);
PAINT PINK (-2150 3725);
QUIT
